FILE_TYPE = MACRO_DRAWING;
SET COLOR_WIRE YELLOW;
SET COLOR_PROP MONO;
SET COLOR_DOT WHITE;
SET COLOR_ARC YELLOW;
SET COLOR_BODY GREEN;
SET COLOR_NOTE MONO;
SET PROP_DISPLAY VALUE;
SET PAGE_NUMBER P207;
FORCEADD OFFPAGE..2
(-1475 4750);
FORCEPROP 2 LAST $XR0 206 
J 0
(-1286 4750);
DISPLAY 0.638298 (-1286 4750);
PAINT MONO (-1286 4750);
FORCEPROP 2 LAST BOM_COST PROC_VRD_VCCIN_CPU0
J 0
(-1275 4800);
DISPLAY 1.446809 (-1275 4800);
PAINT MONO (-1275 4800);
DISPLAY INVISIBLE (-1275 4800);
FORCEPROP 2 LAST PATH I1
J 0
(-1270 4800);
DISPLAY 1.021277 (-1270 4800);
PAINT ORANGE (-1270 4800);
DISPLAY INVISIBLE (-1270 4800);
FORCEPROP 2 LAST CDS_LIB mstr_standard
J 2
(-1475 4750);
DISPLAY 1.936170 (-1475 4750);
PAINT ORANGE (-1475 4750);
DISPLAY INVISIBLE (-1475 4750);
FORCEPROP 2 LAST ROOM PVCCIN_CPU1_PWR_VR
J 0
(-1875 4825);
DISPLAY 1.936170 (-1875 4825);
PAINT ORANGE (-1875 4825);
DISPLAY INVISIBLE (-1875 4825);
FORCEPROP 1 LAST OFFPAGE TRUE
J 0
(-1150 4625);
DISPLAY 1.723404 (-1150 4625);
PAINT GREEN (-1150 4625);
DISPLAY INVISIBLE (-1150 4625);
FORCEPROP 1 LAST COMMENT_BODY TRUE
J 0
(-1520 4655);
DISPLAY 1.723404 (-1520 4655);
PAINT GREEN (-1520 4655);
DISPLAY INVISIBLE (-1520 4655);
FORCEADD RES..1
(-4700 1025);
FORCEPROP 1 LAST WATTAGE 1/10W
J 2
(-4300 875);
DISPLAY 0.617021 (-4300 875);
PAINT SKYBLUE (-4300 875);
FORCEPROP 1 LAST MATERIAL CHIP
J 0
(-4400 925);
DISPLAY 0.617021 (-4400 925);
PAINT SKYBLUE (-4400 925);
FORCEPROP 1 LAST TOLERANCE 5.0%
J 0
(-4400 975);
DISPLAY 0.617021 (-4400 975);
PAINT SKYBLUE (-4400 975);
FORCEPROP 1 LASTPIN (-4800 1025) $PN 1
J 0
(-4788 1037);
DISPLAY 0.787234 (-4788 1037);
PAINT ORANGE (-4788 1037);
FORCEPROP 1 LAST VALUE 0
J 2
(-4750 975);
DISPLAY 0.617021 (-4750 975);
PAINT SKYBLUE (-4750 975);
FORCEPROP 1 LAST PART_NUMBER G22178-002
J 0
(-4800 900);
DISPLAY 0.617021 (-4800 900);
PAINT BLUE (-4800 900);
FORCEPROP 1 LAST LOCATION RT17
J 0
(-4600 1050);
DISPLAY 0.617021 (-4600 1050);
PAINT AQUA (-4600 1050);
FORCEPROP 1 LASTPIN (-4600 1025) $PN 2
J 0
(-4638 1037);
DISPLAY 0.787234 (-4638 1037);
PAINT ORANGE (-4638 1037);
FORCEPROP 1 LAST PACK_TYPE 0603
J 0
(-4625 975);
DISPLAY 0.617021 (-4625 975);
PAINT SKYBLUE (-4625 975);
FORCEPROP 0 LAST ROOM NIC_SPRV
J 0
(-4600 1150);
DISPLAY 1.021277 (-4600 1150);
PAINT ORANGE (-4600 1150);
DISPLAY INVISIBLE (-4600 1150);
FORCEPROP 0 LAST BOM_COST NT_GBE_BASE
J 0
(-4600 1250);
DISPLAY 1.021277 (-4600 1250);
PAINT ORANGE (-4600 1250);
DISPLAY INVISIBLE (-4600 1250);
FORCEPROP 1 LAST PATH I100
J 0
(-4750 1175);
DISPLAY 0.978723 (-4750 1175);
PAINT WHITE (-4750 1175);
DISPLAY INVISIBLE (-4750 1175);
FORCEPROP 2 LAST CDS_LIB mstr_discrete
J 0
(-4700 1025);
PAINT MONO (-4700 1025);
DISPLAY INVISIBLE (-4700 1025);
FORCEPROP 2 LAST SEC_TYPE 0603
J 0
(-4750 1225);
DISPLAY 1.021277 (-4750 1225);
PAINT ORANGE (-4750 1225);
DISPLAY INVISIBLE (-4750 1225);
FORCEPROP 0 LAST SEC 1
J 0
(-4950 1125);
DISPLAY 0.680851 (-4950 1125);
PAINT MONO (-4950 1125);
DISPLAY INVISIBLE (-4950 1125);
FORCEADD RES..1
(-5300 2050);
FORCEPROP 1 LASTPIN (-5400 2050) $PN 1
J 0
(-5388 2062);
DISPLAY 0.617021 (-5388 2062);
PAINT WHITE (-5388 2062);
FORCEPROP 1 LAST LOCATION R9R11
J 0
(-5400 2000);
DISPLAY 0.617021 (-5400 2000);
PAINT AQUA (-5400 2000);
FORCEPROP 1 LAST PART_NUMBER G21497-005
J 0
(-5400 1850);
DISPLAY 0.617021 (-5400 1850);
PAINT BLUE (-5400 1850);
FORCEPROP 1 LAST PACK_TYPE 0402
J 0
(-5250 1950);
DISPLAY 0.617021 (-5250 1950);
PAINT SKYBLUE (-5250 1950);
FORCEPROP 1 LAST TOLERANCE 5%
J 0
(-5400 1900);
DISPLAY 0.617021 (-5400 1900);
PAINT SKYBLUE (-5400 1900);
FORCEPROP 1 LAST WATTAGE 1/16W
J 0
(-5250 2000);
DISPLAY 0.510638 (-5250 2000);
PAINT SKYBLUE (-5250 2000);
FORCEPROP 1 LAST VALUE 0.0
J 0
(-5400 1950);
DISPLAY 0.617021 (-5400 1950);
PAINT SKYBLUE (-5400 1950);
FORCEPROP 1 LAST MATERIAL CHIP
J 0
(-5250 1900);
DISPLAY 0.510638 (-5250 1900);
PAINT SKYBLUE (-5250 1900);
FORCEPROP 1 LASTPIN (-5200 2050) $PN 2
J 0
(-5238 2062);
DISPLAY 0.617021 (-5238 2062);
PAINT WHITE (-5238 2062);
FORCEPROP 2 LAST CDS_LOCATION R9R11
J 0
(-5775 2050);
DISPLAY 0.617021 (-5775 2050);
PAINT AQUA (-5775 2050);
DISPLAY INVISIBLE (-5775 2050);
FORCEPROP 0 LAST CDS_SEC 1
J 0
(-5000 2100);
PAINT MONO (-5000 2100);
DISPLAY INVISIBLE (-5000 2100);
FORCEPROP 2 LAST ROOM CPU0
J 0
(-5350 2200);
PAINT PEACH (-5350 2200);
DISPLAY INVISIBLE (-5350 2200);
FORCEPROP 2 LAST SEC 1
J 0
(-5350 2275);
DISPLAY 0.680851 (-5350 2275);
PAINT MONO (-5350 2275);
DISPLAY INVISIBLE (-5350 2275);
FORCEPROP 2 LAST SEC_TYPE 0402
J 0
(-5350 2275);
DISPLAY 1.021277 (-5350 2275);
PAINT ORANGE (-5350 2275);
DISPLAY INVISIBLE (-5350 2275);
FORCEPROP 2 LAST CDS_LIB mstr_discrete
J 0
(-5300 2050);
DISPLAY 1.340426 (-5300 2050);
PAINT ORANGE (-5300 2050);
DISPLAY INVISIBLE (-5300 2050);
FORCEPROP 2 LAST BOM_COST PROC_SIDEBAND
J 0
(-5300 2050);
PAINT MONO (-5300 2050);
DISPLAY INVISIBLE (-5300 2050);
FORCEPROP 1 LAST PATH I105
J 0
(-5350 2200);
DISPLAY 0.978723 (-5350 2200);
PAINT WHITE (-5350 2200);
DISPLAY INVISIBLE (-5350 2200);
FORCEADD RES..1
(-5400 4650);
FORCEPROP 1 LAST WATTAGE 1/16W
J 0
(-5350 4600);
DISPLAY 0.510638 (-5350 4600);
PAINT SKYBLUE (-5350 4600);
FORCEPROP 1 LAST PACK_TYPE 0402
J 0
(-5350 4550);
DISPLAY 0.617021 (-5350 4550);
PAINT SKYBLUE (-5350 4550);
FORCEPROP 1 LAST MATERIAL CHIP
J 0
(-5350 4500);
DISPLAY 0.510638 (-5350 4500);
PAINT SKYBLUE (-5350 4500);
FORCEPROP 1 LAST VALUE 0.0
J 0
(-5500 4550);
DISPLAY 0.617021 (-5500 4550);
PAINT SKYBLUE (-5500 4550);
FORCEPROP 1 LAST TOLERANCE 5%
J 0
(-5500 4500);
DISPLAY 0.617021 (-5500 4500);
PAINT SKYBLUE (-5500 4500);
FORCEPROP 1 LAST PART_NUMBER G21497-005
J 0
(-5500 4450);
DISPLAY 0.617021 (-5500 4450);
PAINT BLUE (-5500 4450);
FORCEPROP 1 LAST LOCATION R9R2
J 0
(-5500 4600);
DISPLAY 0.617021 (-5500 4600);
PAINT AQUA (-5500 4600);
FORCEPROP 1 LASTPIN (-5300 4650) $PN 2
J 0
(-5338 4662);
DISPLAY 0.617021 (-5338 4662);
PAINT WHITE (-5338 4662);
FORCEPROP 1 LASTPIN (-5500 4650) $PN 1
J 0
(-5488 4662);
DISPLAY 0.617021 (-5488 4662);
PAINT WHITE (-5488 4662);
FORCEPROP 2 LAST BOM_COST PROC_SIDEBAND
J 0
(-5400 4650);
PAINT MONO (-5400 4650);
DISPLAY INVISIBLE (-5400 4650);
FORCEPROP 2 LAST CDS_LIB mstr_discrete
J 0
(-5400 4650);
DISPLAY 1.340426 (-5400 4650);
PAINT ORANGE (-5400 4650);
DISPLAY INVISIBLE (-5400 4650);
FORCEPROP 2 LAST SEC_TYPE 0402
J 0
(-5450 4875);
DISPLAY 1.021277 (-5450 4875);
PAINT ORANGE (-5450 4875);
DISPLAY INVISIBLE (-5450 4875);
FORCEPROP 2 LAST SEC 1
J 0
(-5450 4875);
DISPLAY 0.680851 (-5450 4875);
PAINT MONO (-5450 4875);
DISPLAY INVISIBLE (-5450 4875);
FORCEPROP 2 LAST ROOM CPU0
J 0
(-5450 4800);
PAINT PEACH (-5450 4800);
DISPLAY INVISIBLE (-5450 4800);
FORCEPROP 0 LAST CDS_SEC 1
J 0
(-5100 4700);
PAINT MONO (-5100 4700);
DISPLAY INVISIBLE (-5100 4700);
FORCEPROP 1 LAST PATH I106
J 0
(-5450 4800);
DISPLAY 0.978723 (-5450 4800);
PAINT WHITE (-5450 4800);
DISPLAY INVISIBLE (-5450 4800);
FORCEPROP 2 LAST CDS_LOCATION R9R2
J 0
(-5875 4650);
DISPLAY 0.617021 (-5875 4650);
PAINT AQUA (-5875 4650);
DISPLAY INVISIBLE (-5875 4650);
FORCEADD IND-120NH-30-GP..1
R 1
(-1475 3575);
FORCEPROP 2 LAST TYPE IRMS=66A@DELTA_T<40C
J 0
(-1625 3325);
DISPLAY 0.638298 (-1625 3325);
PAINT GREEN (-1625 3325);
FORCEPROP 1 LAST VALUE IND-120NH-30-GP
J 0
(-1625 3475);
DISPLAY 0.617021 (-1625 3475);
PAINT GREEN (-1625 3475);
FORCEPROP 2 LAST RATED ISAT=94A@25C
J 0
(-1625 3375);
DISPLAY 0.638298 (-1625 3375);
PAINT GREEN (-1625 3375);
FORCEPROP 2 LAST PACK_SIZE DCR=0.17MOHM
J 0
(-1625 3275);
DISPLAY 0.638298 (-1625 3275);
PAINT GREEN (-1625 3275);
FORCEPROP 2 LAST ATTRIBUTE 120NH
J 0
(-1625 3425);
DISPLAY 0.638298 (-1625 3425);
PAINT GREEN (-1625 3425);
FORCEPROP 2 LASTPIN (-1325 3550) $PN 2
J 0
(-1315 3560);
DISPLAY 0.808511 (-1315 3560);
PAINT ORANGE (-1315 3560);
FORCEPROP 1 LAST LOCATION L1E1
J 0
(-1625 3625);
DISPLAY 0.617021 (-1625 3625);
PAINT GREEN (-1625 3625);
FORCEPROP 2 LASTPIN (-1625 3550) $PN 1
J 2
(-1635 3560);
DISPLAY 0.808511 (-1635 3560);
PAINT ORANGE (-1635 3560);
FORCEPROP 1 LAST PART_NUMBER 068.1202N.M001
R 1
J 0
(-1475 3575);
DISPLAY 0.617021 (-1475 3575);
PAINT GREEN (-1475 3575);
DISPLAY INVISIBLE (-1475 3575);
FORCEPROP 2 LAST CDS_LIB w_hdl
R 1
J 0
(-1475 3575);
PAINT MONO (-1475 3575);
DISPLAY INVISIBLE (-1475 3575);
FORCEPROP 1 LAST CDS_LMAN_SYM_OUTLINE -75,100,75,-100
R 1
J 0
(-1475 3575);
DISPLAY 0.468085 (-1475 3575);
PAINT GREEN (-1475 3575);
DISPLAY INVISIBLE (-1475 3575);
FORCEPROP 2 LAST SEC_TYPE DISCRET-GB2
J 0
(-1600 3650);
DISPLAY 1.021277 (-1600 3650);
PAINT ORANGE (-1600 3650);
DISPLAY INVISIBLE (-1600 3650);
FORCEPROP 2 LAST SEC 1
J 0
(-1600 3650);
DISPLAY 0.680851 (-1600 3650);
PAINT MONO (-1600 3650);
DISPLAY INVISIBLE (-1600 3650);
FORCEPROP 1 LAST PACK_TYPE DISCRET-GB2
R 1
J 0
(-1475 3575);
DISPLAY 0.617021 (-1475 3575);
PAINT GREEN (-1475 3575);
DISPLAY INVISIBLE (-1475 3575);
FORCEPROP 1 LAST PATH I107
R 1
J 0
(-1475 3575);
DISPLAY 0.617021 (-1475 3575);
PAINT GREEN (-1475 3575);
DISPLAY INVISIBLE (-1475 3575);
FORCEADD IND-120NH-30-GP..1
R 1
(-1425 975);
FORCEPROP 2 LAST PACK_SIZE DCR=0.17MOHM
J 0
(-1575 675);
DISPLAY 0.638298 (-1575 675);
PAINT GREEN (-1575 675);
FORCEPROP 2 LAST ATTRIBUTE 120NH
J 0
(-1575 825);
DISPLAY 0.638298 (-1575 825);
PAINT GREEN (-1575 825);
FORCEPROP 2 LASTPIN (-1575 950) $PN 1
J 2
(-1585 960);
DISPLAY 0.808511 (-1585 960);
PAINT ORANGE (-1585 960);
FORCEPROP 1 LAST LOCATION L1D3
J 0
(-1575 1025);
DISPLAY 0.617021 (-1575 1025);
PAINT GREEN (-1575 1025);
FORCEPROP 2 LASTPIN (-1275 950) $PN 2
J 0
(-1265 960);
DISPLAY 0.808511 (-1265 960);
PAINT ORANGE (-1265 960);
FORCEPROP 1 LAST VALUE IND-120NH-30-GP
J 0
(-1575 875);
DISPLAY 0.617021 (-1575 875);
PAINT GREEN (-1575 875);
FORCEPROP 2 LAST RATED ISAT=94A@25C
J 0
(-1575 775);
DISPLAY 0.638298 (-1575 775);
PAINT GREEN (-1575 775);
FORCEPROP 2 LAST TYPE IRMS=66A@DELTA_T<40C
J 0
(-1575 725);
DISPLAY 0.638298 (-1575 725);
PAINT GREEN (-1575 725);
FORCEPROP 1 LAST PART_NUMBER 068.1202N.M001
R 1
J 0
(-1425 975);
DISPLAY 0.617021 (-1425 975);
PAINT GREEN (-1425 975);
DISPLAY INVISIBLE (-1425 975);
FORCEPROP 2 LAST CDS_LIB w_hdl
R 1
J 0
(-1425 975);
PAINT MONO (-1425 975);
DISPLAY INVISIBLE (-1425 975);
FORCEPROP 1 LAST CDS_LMAN_SYM_OUTLINE -75,100,75,-100
R 1
J 0
(-1425 975);
DISPLAY 0.468085 (-1425 975);
PAINT GREEN (-1425 975);
DISPLAY INVISIBLE (-1425 975);
FORCEPROP 2 LAST SEC_TYPE DISCRET-GB2
J 0
(-1550 1050);
DISPLAY 1.021277 (-1550 1050);
PAINT ORANGE (-1550 1050);
DISPLAY INVISIBLE (-1550 1050);
FORCEPROP 2 LAST SEC 1
J 0
(-1550 1050);
DISPLAY 0.680851 (-1550 1050);
PAINT MONO (-1550 1050);
DISPLAY INVISIBLE (-1550 1050);
FORCEPROP 1 LAST PACK_TYPE DISCRET-GB2
R 1
J 0
(-1425 975);
DISPLAY 0.617021 (-1425 975);
PAINT GREEN (-1425 975);
DISPLAY INVISIBLE (-1425 975);
FORCEPROP 1 LAST PATH I108
R 1
J 0
(-1425 975);
DISPLAY 0.617021 (-1425 975);
PAINT GREEN (-1425 975);
DISPLAY INVISIBLE (-1425 975);
FORCEADD SC1U10V2KX-4-GP..1
(-5000 1575);
FORCEPROP 1 LAST LOCATION C1E23
J 0
(-4875 1655);
DISPLAY 0.617021 (-4875 1655);
PAINT GREEN (-4875 1655);
FORCEPROP 1 LAST VALUE SC1U10V2KX-4-GP
R 1
J 0
(-4900 1325);
DISPLAY 0.617021 (-4900 1325);
PAINT GREEN (-4900 1325);
FORCEPROP 2 LAST PACK_SIZE 0402
J 0
(-4875 1450);
DISPLAY 0.638298 (-4875 1450);
PAINT GREEN (-4875 1450);
FORCEPROP 2 LAST RATED 10V
J 0
(-4875 1500);
DISPLAY 0.638298 (-4875 1500);
PAINT GREEN (-4875 1500);
FORCEPROP 2 LAST TOLERANCE 10%
J 0
(-4875 1550);
DISPLAY 0.638298 (-4875 1550);
PAINT GREEN (-4875 1550);
FORCEPROP 2 LAST ATTRIBUTE 1UF
J 0
(-4875 1600);
DISPLAY 0.638298 (-4875 1600);
PAINT GREEN (-4875 1600);
FORCEPROP 2 LASTPIN (-5000 1650) $PN 1
R 1
J 0
(-5010 1660);
DISPLAY 0.808511 (-5010 1660);
PAINT ORANGE (-5010 1660);
FORCEPROP 2 LASTPIN (-5000 1500) $PN 2
R 1
J 2
(-5010 1490);
DISPLAY 0.808511 (-5010 1490);
PAINT ORANGE (-5010 1490);
FORCEPROP 1 LAST CDS_LMAN_SYM_OUTLINE -50,25,50,-25
J 0
(-5000 1575);
DISPLAY 0.468085 (-5000 1575);
PAINT GREEN (-5000 1575);
DISPLAY INVISIBLE (-5000 1575);
FORCEPROP 1 LAST PATH I109
J 0
(-5000 1575);
DISPLAY 0.617021 (-5000 1575);
PAINT GREEN (-5000 1575);
DISPLAY INVISIBLE (-5000 1575);
FORCEPROP 2 LAST CDS_LIB w_hdl
J 0
(-5000 1575);
PAINT MONO (-5000 1575);
DISPLAY INVISIBLE (-5000 1575);
FORCEPROP 1 LAST PART_NUMBER 78.10523.8FL
J 0
(-5000 1575);
DISPLAY 0.617021 (-5000 1575);
PAINT GREEN (-5000 1575);
DISPLAY INVISIBLE (-5000 1575);
FORCEPROP 2 LAST SEC_TYPE SMD-BCG6
J 0
(-4975 1650);
DISPLAY 1.021277 (-4975 1650);
PAINT ORANGE (-4975 1650);
DISPLAY INVISIBLE (-4975 1650);
FORCEPROP 2 LAST SEC 1
J 0
(-4975 1650);
DISPLAY 0.680851 (-4975 1650);
PAINT MONO (-4975 1650);
DISPLAY INVISIBLE (-4975 1650);
FORCEPROP 1 LAST PACK_TYPE SMD-BCG6
J 0
(-5000 1575);
DISPLAY 0.617021 (-5000 1575);
PAINT GREEN (-5000 1575);
DISPLAY INVISIBLE (-5000 1575);
FORCEADD OFFPAGE..2
(-975 2275);
FORCEPROP 2 LAST $XR0 206 
J 0
(-786 2275);
DISPLAY 0.638298 (-786 2275);
PAINT MONO (-786 2275);
FORCEPROP 2 LAST BOM_COST PROC_VRD_VCCIN_CPU0
J 0
(-775 2325);
DISPLAY 1.446809 (-775 2325);
PAINT MONO (-775 2325);
DISPLAY INVISIBLE (-775 2325);
FORCEPROP 2 LAST PATH I11
J 0
(-770 2325);
DISPLAY 1.021277 (-770 2325);
PAINT ORANGE (-770 2325);
DISPLAY INVISIBLE (-770 2325);
FORCEPROP 2 LAST CDS_LIB mstr_standard
J 0
(-975 2275);
PAINT ORANGE (-975 2275);
DISPLAY INVISIBLE (-975 2275);
FORCEPROP 2 LAST ROOM PVCCIN_CPU1_PWR_VR
J 0
(-1375 2350);
DISPLAY 1.936170 (-1375 2350);
PAINT ORANGE (-1375 2350);
DISPLAY INVISIBLE (-1375 2350);
FORCEPROP 1 LAST OFFPAGE TRUE
J 0
(-650 2150);
DISPLAY 1.723404 (-650 2150);
PAINT GREEN (-650 2150);
DISPLAY INVISIBLE (-650 2150);
FORCEPROP 1 LAST COMMENT_BODY TRUE
J 0
(-1020 2180);
DISPLAY 1.723404 (-1020 2180);
PAINT GREEN (-1020 2180);
DISPLAY INVISIBLE (-1020 2180);
FORCEADD SC1U10V2KX-4-GP..1
(-5100 4125);
FORCEPROP 2 LAST TOLERANCE 10%
J 0
(-4975 4100);
DISPLAY 0.638298 (-4975 4100);
PAINT GREEN (-4975 4100);
FORCEPROP 2 LAST ATTRIBUTE 1UF
J 0
(-4975 4150);
DISPLAY 0.638298 (-4975 4150);
PAINT GREEN (-4975 4150);
FORCEPROP 1 LAST LOCATION C1E6
J 0
(-4975 4205);
DISPLAY 0.617021 (-4975 4205);
PAINT GREEN (-4975 4205);
FORCEPROP 2 LASTPIN (-5100 4050) $PN 2
R 1
J 2
(-5110 4040);
DISPLAY 0.808511 (-5110 4040);
PAINT ORANGE (-5110 4040);
FORCEPROP 2 LASTPIN (-5100 4200) $PN 1
R 1
J 0
(-5110 4210);
DISPLAY 0.808511 (-5110 4210);
PAINT ORANGE (-5110 4210);
FORCEPROP 2 LAST PACK_SIZE 0402
J 0
(-4975 4000);
DISPLAY 0.638298 (-4975 4000);
PAINT GREEN (-4975 4000);
FORCEPROP 2 LAST RATED 10V
J 0
(-4975 4050);
DISPLAY 0.638298 (-4975 4050);
PAINT GREEN (-4975 4050);
FORCEPROP 1 LAST VALUE SC1U10V2KX-4-GP
R 1
J 0
(-5000 3900);
DISPLAY 0.617021 (-5000 3900);
PAINT GREEN (-5000 3900);
FORCEPROP 1 LAST PACK_TYPE SMD-BCG6
J 0
(-5100 4125);
DISPLAY 0.617021 (-5100 4125);
PAINT GREEN (-5100 4125);
DISPLAY INVISIBLE (-5100 4125);
FORCEPROP 2 LAST SEC 1
J 0
(-5075 4200);
DISPLAY 0.680851 (-5075 4200);
PAINT MONO (-5075 4200);
DISPLAY INVISIBLE (-5075 4200);
FORCEPROP 2 LAST SEC_TYPE SMD-BCG6
J 0
(-5075 4200);
DISPLAY 1.021277 (-5075 4200);
PAINT ORANGE (-5075 4200);
DISPLAY INVISIBLE (-5075 4200);
FORCEPROP 1 LAST PART_NUMBER 78.10523.8FL
J 0
(-5100 4125);
DISPLAY 0.617021 (-5100 4125);
PAINT GREEN (-5100 4125);
DISPLAY INVISIBLE (-5100 4125);
FORCEPROP 2 LAST CDS_LIB w_hdl
J 0
(-5100 4125);
PAINT MONO (-5100 4125);
DISPLAY INVISIBLE (-5100 4125);
FORCEPROP 1 LAST PATH I110
J 0
(-5100 4125);
DISPLAY 0.617021 (-5100 4125);
PAINT GREEN (-5100 4125);
DISPLAY INVISIBLE (-5100 4125);
FORCEPROP 1 LAST CDS_LMAN_SYM_OUTLINE -50,25,50,-25
J 0
(-5100 4125);
DISPLAY 0.468085 (-5100 4125);
PAINT GREEN (-5100 4125);
DISPLAY INVISIBLE (-5100 4125);
FORCEADD 1R3F-GP..1
(-2225 3050);
FORCEPROP 1 LAST LOCATION RT16
J 0
(-2175 3175);
DISPLAY 0.617021 (-2175 3175);
PAINT GREEN (-2175 3175);
FORCEPROP 2 LAST PACK_SIZE 0603
J 0
(-2175 2925);
DISPLAY 0.638298 (-2175 2925);
PAINT GREEN (-2175 2925);
FORCEPROP 2 LAST RATED 1/10W
J 0
(-2175 2975);
DISPLAY 0.638298 (-2175 2975);
PAINT GREEN (-2175 2975);
FORCEPROP 2 LAST ATTRIBUTE 1 OHM
J 0
(-2175 3075);
DISPLAY 0.638298 (-2175 3075);
PAINT GREEN (-2175 3075);
FORCEPROP 2 LASTPIN (-2225 2925) $PN 2
R 1
J 2
(-2235 2915);
DISPLAY 0.808511 (-2235 2915);
PAINT ORANGE (-2235 2915);
FORCEPROP 2 LASTPIN (-2225 3175) $PN 1
R 1
J 0
(-2235 3185);
DISPLAY 0.808511 (-2235 3185);
PAINT ORANGE (-2235 3185);
FORCEPROP 0 LAST POP NOPOP
J 0
(-2175 2875);
DISPLAY 0.638298 (-2175 2875);
PAINT RED (-2175 2875);
FORCEPROP 2 LAST TOLERANCE 1%
J 0
(-2175 3025);
DISPLAY 0.638298 (-2175 3025);
PAINT GREEN (-2175 3025);
FORCEPROP 1 LAST VALUE 1R3F-GP
J 0
(-2175 3125);
DISPLAY 0.617021 (-2175 3125);
PAINT GREEN (-2175 3125);
FORCEPROP 1 LAST PACK_TYPE RCL_GP
J 0
(-2225 3050);
DISPLAY 0.617021 (-2225 3050);
PAINT GREEN (-2225 3050);
DISPLAY INVISIBLE (-2225 3050);
FORCEPROP 2 LAST SEC 1
J 0
(-2175 3150);
DISPLAY 0.680851 (-2175 3150);
PAINT MONO (-2175 3150);
DISPLAY INVISIBLE (-2175 3150);
FORCEPROP 2 LAST SEC_TYPE RCL_GP
J 0
(-2175 3150);
DISPLAY 1.021277 (-2175 3150);
PAINT ORANGE (-2175 3150);
DISPLAY INVISIBLE (-2175 3150);
FORCEPROP 1 LAST PART_NUMBER 64.1R005.55L
J 0
(-2225 3050);
DISPLAY 0.617021 (-2225 3050);
PAINT GREEN (-2225 3050);
DISPLAY INVISIBLE (-2225 3050);
FORCEPROP 2 LAST CDS_LIB w_hdl
J 0
(-2225 3050);
DISPLAY INVISIBLE (-2225 3050);
FORCEPROP 1 LAST CDS_LMAN_SYM_OUTLINE -50,75,50,-75
J 0
(-2225 3050);
DISPLAY 0.468085 (-2225 3050);
PAINT GREEN (-2225 3050);
DISPLAY INVISIBLE (-2225 3050);
FORCEPROP 1 LAST PATH I111
J 0
(-2225 3050);
DISPLAY 0.617021 (-2225 3050);
PAINT GREEN (-2225 3050);
DISPLAY INVISIBLE (-2225 3050);
FORCEADD 1R3F-GP..1
(-1925 550);
FORCEPROP 2 LAST PACK_SIZE 0603
J 0
(-1875 425);
DISPLAY 0.638298 (-1875 425);
PAINT GREEN (-1875 425);
FORCEPROP 1 LAST VALUE 1R3F-GP
J 0
(-1875 625);
DISPLAY 0.617021 (-1875 625);
PAINT GREEN (-1875 625);
FORCEPROP 2 LAST ATTRIBUTE 1 OHM
J 0
(-1875 575);
DISPLAY 0.638298 (-1875 575);
PAINT GREEN (-1875 575);
FORCEPROP 2 LAST RATED 1/10W
J 0
(-1875 475);
DISPLAY 0.638298 (-1875 475);
PAINT GREEN (-1875 475);
FORCEPROP 0 LAST POP NOPOP
J 0
(-1875 375);
DISPLAY 0.638298 (-1875 375);
PAINT RED (-1875 375);
FORCEPROP 1 LAST LOCATION RT18
J 0
(-2050 625);
DISPLAY 0.617021 (-2050 625);
PAINT GREEN (-2050 625);
FORCEPROP 2 LAST TOLERANCE 1%
J 0
(-1875 525);
DISPLAY 0.638298 (-1875 525);
PAINT GREEN (-1875 525);
FORCEPROP 2 LASTPIN (-1925 675) $PN 1
R 1
J 0
(-1935 685);
DISPLAY 0.808511 (-1935 685);
PAINT ORANGE (-1935 685);
FORCEPROP 2 LASTPIN (-1925 425) $PN 2
R 1
J 2
(-1935 415);
DISPLAY 0.808511 (-1935 415);
PAINT ORANGE (-1935 415);
FORCEPROP 1 LAST CDS_LMAN_SYM_OUTLINE -50,75,50,-75
J 0
(-1925 550);
DISPLAY 0.468085 (-1925 550);
PAINT GREEN (-1925 550);
DISPLAY INVISIBLE (-1925 550);
FORCEPROP 2 LAST CDS_LIB w_hdl
J 0
(-1925 550);
DISPLAY INVISIBLE (-1925 550);
FORCEPROP 1 LAST PART_NUMBER 64.1R005.55L
J 0
(-1925 550);
DISPLAY 0.617021 (-1925 550);
PAINT GREEN (-1925 550);
DISPLAY INVISIBLE (-1925 550);
FORCEPROP 2 LAST SEC_TYPE RCL_GP
J 0
(-1875 650);
DISPLAY 1.021277 (-1875 650);
PAINT ORANGE (-1875 650);
DISPLAY INVISIBLE (-1875 650);
FORCEPROP 2 LAST SEC 1
J 0
(-1875 650);
DISPLAY 0.680851 (-1875 650);
PAINT MONO (-1875 650);
DISPLAY INVISIBLE (-1875 650);
FORCEPROP 1 LAST PACK_TYPE RCL_GP
J 0
(-1925 550);
DISPLAY 0.617021 (-1925 550);
PAINT GREEN (-1925 550);
DISPLAY INVISIBLE (-1925 550);
FORCEPROP 1 LAST PATH I112
J 0
(-1925 550);
DISPLAY 0.617021 (-1925 550);
PAINT GREEN (-1925 550);
DISPLAY INVISIBLE (-1925 550);
FORCEADD IR354XX..1
(-3150 1250);
FORCEPROP 2 LASTPIN (-3650 1500) $PN 35
J 2
(-3660 1510);
DISPLAY 0.617021 (-3660 1510);
PAINT ORANGE (-3660 1510);
FORCEPROP 1 LAST MATERIAL IC
J 0
(-3600 1975);
DISPLAY 0.617021 (-3600 1975);
PAINT SKYBLUE (-3600 1975);
FORCEPROP 2 LASTPIN (-2650 800) $PN 40
J 0
(-2640 810);
DISPLAY 0.617021 (-2640 810);
PAINT ORANGE (-2640 810);
FORCEPROP 2 LASTPIN (-2650 750) $PN 7
J 0
(-2640 760);
DISPLAY 0.617021 (-2640 760);
PAINT ORANGE (-2640 760);
FORCEPROP 2 LASTPIN (-2650 950) $PN 10
J 0
(-2640 960);
DISPLAY 0.617021 (-2640 960);
PAINT ORANGE (-2640 960);
FORCEPROP 2 LASTPIN (-2650 1300) $PN 36
J 0
(-2640 1310);
DISPLAY 0.617021 (-2640 1310);
PAINT ORANGE (-2640 1310);
FORCEPROP 2 LASTPIN (-3650 950) $PN 33
J 2
(-3660 960);
DISPLAY 0.617021 (-3660 960);
PAINT ORANGE (-3660 960);
FORCEPROP 2 LASTPIN (-3650 1250) $PN 6
J 2
(-3660 1260);
DISPLAY 0.617021 (-3660 1260);
PAINT ORANGE (-3660 1260);
FORCEPROP 2 LASTPIN (-3650 1300) $PN 41
J 2
(-3660 1310);
DISPLAY 0.617021 (-3660 1310);
PAINT ORANGE (-3660 1310);
FORCEPROP 2 LASTPIN (-3650 1700) $PN 25
J 2
(-3660 1710);
DISPLAY 0.617021 (-3660 1710);
PAINT ORANGE (-3660 1710);
FORCEPROP 2 LASTPIN (-3650 1600) $PN 4
J 2
(-3660 1610);
DISPLAY 0.617021 (-3660 1610);
PAINT ORANGE (-3660 1610);
FORCEPROP 2 LASTPIN (-3650 1750) $PN 30
J 2
(-3660 1760);
DISPLAY 0.617021 (-3660 1760);
PAINT ORANGE (-3660 1760);
FORCEPROP 2 LASTPIN (-3650 1800) $PN 3
J 2
(-3660 1810);
DISPLAY 0.617021 (-3660 1810);
PAINT ORANGE (-3660 1810);
FORCEPROP 2 LASTPIN (-2650 700) $PN 5
J 0
(-2640 710);
DISPLAY 0.617021 (-2640 710);
PAINT ORANGE (-2640 710);
FORCEPROP 2 LASTPIN (-2650 1600) $PN 37
J 0
(-2640 1610);
DISPLAY 0.617021 (-2640 1610);
PAINT ORANGE (-2640 1610);
FORCEPROP 2 LASTPIN (-2650 1800) $PN 38
J 0
(-2640 1810);
DISPLAY 0.617021 (-2640 1810);
PAINT ORANGE (-2640 1810);
FORCEPROP 2 LASTPIN (-2650 1550) $PN 31
J 0
(-2640 1560);
DISPLAY 0.617021 (-2640 1560);
PAINT ORANGE (-2640 1560);
FORCEPROP 1 LAST PART_NUMBER H73688-001
J 0
(-3525 550);
DISPLAY 0.617021 (-3525 550);
PAINT BLUE (-3525 550);
FORCEPROP 2 LASTPIN (-3650 1150) $PN 34
J 2
(-3660 1160);
DISPLAY 0.617021 (-3660 1160);
PAINT ORANGE (-3660 1160);
FORCEPROP 2 LASTPIN (-3650 1400) $PN 1
J 2
(-3660 1410);
DISPLAY 0.617021 (-3660 1410);
PAINT ORANGE (-3660 1410);
FORCEPROP 2 LASTPIN (-3650 900) $PN 32
J 2
(-3660 910);
DISPLAY 0.617021 (-3660 910);
PAINT ORANGE (-3660 910);
FORCEPROP 2 LASTPIN (-3650 1050) $PN 39
J 2
(-3660 1060);
DISPLAY 0.617021 (-3660 1060);
PAINT ORANGE (-3660 1060);
FORCEPROP 2 LASTPIN (-2650 850) $PN 2
J 0
(-2640 860);
DISPLAY 0.617021 (-2640 860);
PAINT ORANGE (-2640 860);
FORCEPROP 1 LAST LOCATION EU1D4
J 0
(-3275 1975);
DISPLAY 0.617021 (-3275 1975);
PAINT AQUA (-3275 1975);
FORCEPROP 1 LAST VALUE IR35411
J 1
(-3150 1875);
DISPLAY 0.617021 (-3150 1875);
PAINT SKYBLUE (-3150 1875);
DISPLAY INVISIBLE (-3150 1875);
FORCEPROP 2 LAST ROOM PVCCIN_CPU1_PWR_VR
J 0
(-3400 -375);
DISPLAY 1.361702 (-3400 -375);
PAINT ORANGE (-3400 -375);
DISPLAY INVISIBLE (-3400 -375);
FORCEPROP 2 LAST CDS_LIB mstr_discrete
J 0
(-3150 1250);
PAINT ORANGE (-3150 1250);
DISPLAY INVISIBLE (-3150 1250);
FORCEPROP 1 LAST PACK_TYPE SM
J 0
(-3600 2100);
PAINT SKYBLUE (-3600 2100);
DISPLAY INVISIBLE (-3600 2100);
FORCEPROP 2 LAST SEC 1
J 0
(-3150 2050);
DISPLAY 0.680851 (-3150 2050);
PAINT MONO (-3150 2050);
DISPLAY INVISIBLE (-3150 2050);
FORCEPROP 2 LAST SEC_TYPE SM
J 0
(-3150 2050);
DISPLAY 1.021277 (-3150 2050);
PAINT ORANGE (-3150 2050);
DISPLAY INVISIBLE (-3150 2050);
FORCEPROP 1 LAST PATH I113
J 0
(-3150 2000);
PAINT GREEN (-3150 2000);
DISPLAY INVISIBLE (-3150 2000);
FORCEPROP 2 LAST CDS_LOCATION EU1D4
J 0
(-3275 1975);
DISPLAY 0.765957 (-3275 1975);
PAINT AQUA (-3275 1975);
DISPLAY INVISIBLE (-3275 1975);
FORCEADD OFFPAGE..2
(-1500 1500);
FORCEPROP 2 LAST $XR3 206 
J 0
(-951 1500);
DISPLAY 0.638298 (-951 1500);
PAINT MONO (-951 1500);
FORCEPROP 2 LAST $XR2 209 
J 0
(-1071 1500);
DISPLAY 0.638298 (-1071 1500);
PAINT MONO (-1071 1500);
FORCEPROP 2 LAST $XR1 208 
J 0
(-1191 1500);
DISPLAY 0.638298 (-1191 1500);
PAINT MONO (-1191 1500);
FORCEPROP 2 LAST $XR0 207 
J 0
(-1311 1500);
DISPLAY 0.638298 (-1311 1500);
PAINT MONO (-1311 1500);
FORCEPROP 2 LAST PATH I13
J 0
(-1070 1550);
DISPLAY 1.021277 (-1070 1550);
PAINT ORANGE (-1070 1550);
DISPLAY INVISIBLE (-1070 1550);
FORCEPROP 2 LAST BOM_COST PROC_VRD_VCCIN_CPU0
J 0
(-1300 1550);
DISPLAY 1.446809 (-1300 1550);
PAINT MONO (-1300 1550);
DISPLAY INVISIBLE (-1300 1550);
FORCEPROP 2 LAST CDS_LIB mstr_standard
J 0
(-1500 1500);
PAINT ORANGE (-1500 1500);
DISPLAY INVISIBLE (-1500 1500);
FORCEPROP 2 LAST ROOM PVCCIN_CPU1_PWR_VR
J 0
(-1900 1575);
DISPLAY 1.936170 (-1900 1575);
PAINT ORANGE (-1900 1575);
DISPLAY INVISIBLE (-1900 1575);
FORCEPROP 1 LAST OFFPAGE TRUE
J 0
(-1175 1375);
DISPLAY 1.723404 (-1175 1375);
PAINT GREEN (-1175 1375);
DISPLAY INVISIBLE (-1175 1375);
FORCEPROP 1 LAST COMMENT_BODY TRUE
J 0
(-1545 1405);
DISPLAY 1.723404 (-1545 1405);
PAINT GREEN (-1545 1405);
DISPLAY INVISIBLE (-1545 1405);
FORCEADD PVCCIN_CPU1..1
(-750 1050);
FORCEPROP 3 LASTPIN (-750 1000) SIG_NAME PVCCIN_CPU1\g
J 0
(-740 1010);
DISPLAY 0.659574 (-740 1010);
PAINT MONO (-740 1010);
DISPLAY INVISIBLE (-740 1010);
FORCEPROP 2 LAST CDS_LIB mstr_symbols
J 0
(-750 1050);
PAINT ORANGE (-750 1050);
DISPLAY INVISIBLE (-750 1050);
FORCEPROP 1 LAST PATH I14
J 0
(-700 1075);
DISPLAY 0.872340 (-700 1075);
PAINT AQUA (-700 1075);
DISPLAY INVISIBLE (-700 1075);
FORCEPROP 1 LAST VOLTAGE 2.0V
J 0
(-795 1007);
DISPLAY 0.340426 (-795 1007);
PAINT SKYBLUE (-795 1007);
DISPLAY INVISIBLE (-795 1007);
FORCEPROP 1 LAST BODY_TYPE PLUMBING
J 0
(-795 1007);
DISPLAY 0.340426 (-795 1007);
PAINT GREEN (-795 1007);
DISPLAY INVISIBLE (-795 1007);
FORCEPROP 1 LAST HDL_POWER PVCCIN_CPU1
J 1
(-750 1100);
DISPLAY 0.872340 (-750 1100);
PAINT GREEN (-750 1100);
DISPLAY INVISIBLE (-750 1100);
FORCEADD GND..1
(-750 425);
FORCEPROP 3 LASTPIN (-750 475) SIG_NAME GND\g
J 0
(-740 485);
DISPLAY 0.659574 (-740 485);
PAINT MONO (-740 485);
DISPLAY INVISIBLE (-740 485);
FORCEPROP 1 LAST VOLTAGE 0
J 0
(-750 425);
PAINT SKYBLUE (-750 425);
DISPLAY INVISIBLE (-750 425);
FORCEPROP 2 LAST CDS_LIB mstr_symbols
J 0
(-750 425);
PAINT ORANGE (-750 425);
DISPLAY INVISIBLE (-750 425);
FORCEPROP 1 LAST SIZE 1B
J 0
(-675 375);
DISPLAY 1.723404 (-675 375);
PAINT GREEN (-675 375);
DISPLAY INVISIBLE (-675 375);
FORCEPROP 1 LAST PATH I17
J 0
(-675 425);
DISPLAY 0.872340 (-675 425);
PAINT AQUA (-675 425);
DISPLAY INVISIBLE (-675 425);
FORCEPROP 2 LAST BOM_COST PROC_VRD_VCCIN_CPU0
J 0
(-1125 500);
DISPLAY 1.446809 (-1125 500);
PAINT MONO (-1125 500);
DISPLAY INVISIBLE (-1125 500);
FORCEPROP 2 LAST ROOM PVCCIN_CPU1_PWR_VR
J 0
(-1300 500);
DISPLAY 1.936170 (-1300 500);
PAINT ORANGE (-1300 500);
DISPLAY INVISIBLE (-1300 500);
FORCEPROP 1 LAST BODY_TYPE PLUMBING
J 0
(-795 382);
DISPLAY 0.340426 (-795 382);
PAINT GREEN (-795 382);
DISPLAY INVISIBLE (-795 382);
FORCEPROP 1 LAST HDL_POWER GND
J 0
(-750 575);
DISPLAY 1.723404 (-750 575);
PAINT GREEN (-750 575);
DISPLAY INVISIBLE (-750 575);
FORCEADD CAP_A..1
(-1100 750);
FORCEPROP 1 LASTPIN (-1100 850) $PN 1
J 0
(-1090 830);
DISPLAY 0.617021 (-1090 830);
PAINT ORANGE (-1090 830);
FORCEPROP 1 LASTPIN (-1100 650) $PN 2
J 0
(-1090 630);
DISPLAY 0.617021 (-1090 630);
PAINT ORANGE (-1090 630);
FORCEPROP 1 LAST LOCATION C1E3
J 0
(-1050 900);
DISPLAY 0.617021 (-1050 900);
PAINT AQUA (-1050 900);
FORCEPROP 1 LAST VALUE 22.0UF
J 0
(-1050 850);
DISPLAY 0.617021 (-1050 850);
PAINT SKYBLUE (-1050 850);
FORCEPROP 1 LAST VOLTAGE 4V
J 0
(-1050 800);
DISPLAY 0.617021 (-1050 800);
PAINT SKYBLUE (-1050 800);
FORCEPROP 1 LAST TOLERANCE 20%
J 0
(-1050 750);
DISPLAY 0.617021 (-1050 750);
PAINT SKYBLUE (-1050 750);
FORCEPROP 1 LAST MATERIAL X6S
J 0
(-1050 700);
DISPLAY 0.617021 (-1050 700);
PAINT SKYBLUE (-1050 700);
FORCEPROP 1 LAST PACK_TYPE 0603V
J 0
(-1050 600);
DISPLAY 0.617021 (-1050 600);
PAINT SKYBLUE (-1050 600);
FORCEPROP 1 LAST PART_NUMBER E15431-004
J 0
(-1050 650);
DISPLAY 0.617021 (-1050 650);
PAINT BLUE (-1050 650);
FORCEPROP 0 LAST GROUP PWR_MLCC_CAP
J 0
(-1044 537);
DISPLAY 0.638298 (-1044 537);
PAINT BROWN (-1044 537);
DISPLAY BOTH (-1044 537);
FORCEPROP 2 LAST CDS_LIB dev_discrete
J 0
(-1100 750);
PAINT ORANGE (-1100 750);
DISPLAY INVISIBLE (-1100 750);
FORCEPROP 2 LAST CDS_LOCATION C1E3
J 0
(-1050 850);
DISPLAY 0.617021 (-1050 850);
PAINT AQUA (-1050 850);
DISPLAY INVISIBLE (-1050 850);
FORCEPROP 2 LAST BOM_COST PROC_VRD_VCCIN_CPU0
J 0
(-1050 900);
DISPLAY 1.446809 (-1050 900);
PAINT MONO (-1050 900);
DISPLAY INVISIBLE (-1050 900);
FORCEPROP 2 LAST CDS_SEC 1
J 0
(-1050 900);
PAINT ORANGE (-1050 900);
DISPLAY INVISIBLE (-1050 900);
FORCEPROP 2 LAST SEC_TYPE 0603V
J 0
(-1045 950);
DISPLAY 1.021277 (-1045 950);
PAINT ORANGE (-1045 950);
DISPLAY INVISIBLE (-1045 950);
FORCEPROP 2 LAST SEC 1
J 0
(-1045 950);
DISPLAY 0.680851 (-1045 950);
PAINT MONO (-1045 950);
DISPLAY INVISIBLE (-1045 950);
FORCEPROP 1 LAST PATH I18
J 0
(-1050 900);
DISPLAY 0.978723 (-1050 900);
PAINT WHITE (-1050 900);
DISPLAY INVISIBLE (-1050 900);
FORCEPROP 2 LAST ROOM PVCCIN_CPU1_PWR_VR
J 0
(-1050 900);
DISPLAY 1.446809 (-1050 900);
PAINT MONO (-1050 900);
DISPLAY INVISIBLE (-1050 900);
FORCEADD GND..1
(-2400 3100);
FORCEPROP 3 LASTPIN (-2400 3150) SIG_NAME GND\g
J 0
(-2390 3160);
DISPLAY 0.659574 (-2390 3160);
PAINT MONO (-2390 3160);
DISPLAY INVISIBLE (-2390 3160);
FORCEPROP 1 LAST PATH I19
J 0
(-2325 3100);
DISPLAY 0.872340 (-2325 3100);
PAINT AQUA (-2325 3100);
DISPLAY INVISIBLE (-2325 3100);
FORCEPROP 2 LAST CDS_LIB mstr_symbols
J 0
(-2400 3100);
DISPLAY 1.936170 (-2400 3100);
PAINT ORANGE (-2400 3100);
DISPLAY INVISIBLE (-2400 3100);
FORCEPROP 1 LAST VOLTAGE 0
J 0
(-2400 3100);
PAINT SKYBLUE (-2400 3100);
DISPLAY INVISIBLE (-2400 3100);
FORCEPROP 1 LAST SIZE 1B
J 0
(-2325 3050);
DISPLAY 1.723404 (-2325 3050);
PAINT GREEN (-2325 3050);
DISPLAY INVISIBLE (-2325 3050);
FORCEPROP 2 LAST BOM_COST PROC_VRD_VCCIN_CPU0
J 0
(-2775 3175);
DISPLAY 1.446809 (-2775 3175);
PAINT MONO (-2775 3175);
DISPLAY INVISIBLE (-2775 3175);
FORCEPROP 2 LAST ROOM PVCCIN_CPU1_PWR_VR
J 0
(-2950 3175);
DISPLAY 1.936170 (-2950 3175);
PAINT ORANGE (-2950 3175);
DISPLAY INVISIBLE (-2950 3175);
FORCEPROP 1 LAST BODY_TYPE PLUMBING
J 0
(-2445 3057);
DISPLAY 0.340426 (-2445 3057);
PAINT GREEN (-2445 3057);
DISPLAY INVISIBLE (-2445 3057);
FORCEPROP 1 LAST HDL_POWER GND
J 0
(-2400 3250);
DISPLAY 1.723404 (-2400 3250);
PAINT GREEN (-2400 3250);
DISPLAY INVISIBLE (-2400 3250);
FORCEADD IR354XX..1
(-3125 3850);
FORCEPROP 2 LASTPIN (-2625 3450) $PN 2
J 0
(-2615 3460);
DISPLAY 0.617021 (-2615 3460);
PAINT ORANGE (-2615 3460);
FORCEPROP 2 LASTPIN (-3625 3650) $PN 39
J 2
(-3635 3660);
DISPLAY 0.617021 (-3635 3660);
PAINT ORANGE (-3635 3660);
FORCEPROP 2 LASTPIN (-3625 3500) $PN 32
J 2
(-3635 3510);
DISPLAY 0.617021 (-3635 3510);
PAINT ORANGE (-3635 3510);
FORCEPROP 2 LASTPIN (-3625 4000) $PN 1
J 2
(-3635 4010);
DISPLAY 0.617021 (-3635 4010);
PAINT ORANGE (-3635 4010);
FORCEPROP 2 LASTPIN (-3625 3750) $PN 34
J 2
(-3635 3760);
DISPLAY 0.617021 (-3635 3760);
PAINT ORANGE (-3635 3760);
FORCEPROP 2 LASTPIN (-2625 4150) $PN 31
J 0
(-2615 4160);
DISPLAY 0.617021 (-2615 4160);
PAINT ORANGE (-2615 4160);
FORCEPROP 2 LASTPIN (-2625 4400) $PN 38
J 0
(-2615 4410);
DISPLAY 0.617021 (-2615 4410);
PAINT ORANGE (-2615 4410);
FORCEPROP 2 LASTPIN (-2625 4200) $PN 37
J 0
(-2615 4210);
DISPLAY 0.617021 (-2615 4210);
PAINT ORANGE (-2615 4210);
FORCEPROP 2 LASTPIN (-2625 3300) $PN 5
J 0
(-2615 3310);
DISPLAY 0.617021 (-2615 3310);
PAINT ORANGE (-2615 3310);
FORCEPROP 1 LAST LOCATION EU1E2
J 0
(-3250 4575);
DISPLAY 0.617021 (-3250 4575);
PAINT AQUA (-3250 4575);
FORCEPROP 2 LASTPIN (-3625 4400) $PN 3
J 2
(-3635 4410);
DISPLAY 0.617021 (-3635 4410);
PAINT ORANGE (-3635 4410);
FORCEPROP 2 LASTPIN (-3625 4350) $PN 30
J 2
(-3635 4360);
DISPLAY 0.617021 (-3635 4360);
PAINT ORANGE (-3635 4360);
FORCEPROP 2 LASTPIN (-3625 4200) $PN 4
J 2
(-3635 4210);
DISPLAY 0.617021 (-3635 4210);
PAINT ORANGE (-3635 4210);
FORCEPROP 2 LASTPIN (-3625 4300) $PN 25
J 2
(-3635 4310);
DISPLAY 0.617021 (-3635 4310);
PAINT ORANGE (-3635 4310);
FORCEPROP 2 LASTPIN (-3625 3900) $PN 41
J 2
(-3635 3910);
DISPLAY 0.617021 (-3635 3910);
PAINT ORANGE (-3635 3910);
FORCEPROP 2 LASTPIN (-3625 3850) $PN 6
J 2
(-3635 3860);
DISPLAY 0.617021 (-3635 3860);
PAINT ORANGE (-3635 3860);
FORCEPROP 2 LASTPIN (-3625 3550) $PN 33
J 2
(-3635 3560);
DISPLAY 0.617021 (-3635 3560);
PAINT ORANGE (-3635 3560);
FORCEPROP 2 LASTPIN (-2625 3900) $PN 36
J 0
(-2615 3910);
DISPLAY 0.617021 (-2615 3910);
PAINT ORANGE (-2615 3910);
FORCEPROP 2 LASTPIN (-2625 3550) $PN 10
J 0
(-2615 3560);
DISPLAY 0.617021 (-2615 3560);
PAINT ORANGE (-2615 3560);
FORCEPROP 2 LASTPIN (-2625 3350) $PN 7
J 0
(-2615 3360);
DISPLAY 0.617021 (-2615 3360);
PAINT ORANGE (-2615 3360);
FORCEPROP 2 LASTPIN (-2625 3400) $PN 40
J 0
(-2615 3410);
DISPLAY 0.617021 (-2615 3410);
PAINT ORANGE (-2615 3410);
FORCEPROP 1 LAST MATERIAL IC
J 0
(-3575 4575);
DISPLAY 0.617021 (-3575 4575);
PAINT SKYBLUE (-3575 4575);
FORCEPROP 2 LASTPIN (-3625 4100) $PN 35
J 2
(-3635 4110);
DISPLAY 0.617021 (-3635 4110);
PAINT ORANGE (-3635 4110);
FORCEPROP 1 LAST PART_NUMBER H73688-001
J 0
(-3500 3150);
DISPLAY 0.617021 (-3500 3150);
PAINT BLUE (-3500 3150);
FORCEPROP 2 LAST SEC_TYPE SM
J 0
(-3125 4650);
DISPLAY 1.021277 (-3125 4650);
PAINT ORANGE (-3125 4650);
DISPLAY INVISIBLE (-3125 4650);
FORCEPROP 2 LAST SEC 1
J 0
(-3125 4650);
DISPLAY 0.680851 (-3125 4650);
PAINT MONO (-3125 4650);
DISPLAY INVISIBLE (-3125 4650);
FORCEPROP 2 LAST CDS_LOCATION EU1E2
J 0
(-3250 4575);
DISPLAY 0.765957 (-3250 4575);
PAINT AQUA (-3250 4575);
DISPLAY INVISIBLE (-3250 4575);
FORCEPROP 1 LAST PACK_TYPE SM
J 0
(-3575 4700);
PAINT SKYBLUE (-3575 4700);
DISPLAY INVISIBLE (-3575 4700);
FORCEPROP 2 LAST CDS_LIB mstr_discrete
J 0
(-3125 3850);
PAINT ORANGE (-3125 3850);
DISPLAY INVISIBLE (-3125 3850);
FORCEPROP 2 LAST ROOM PVCCIN_CPU1_PWR_VR
J 0
(-3375 2225);
DISPLAY 1.361702 (-3375 2225);
PAINT ORANGE (-3375 2225);
DISPLAY INVISIBLE (-3375 2225);
FORCEPROP 1 LAST VALUE IR35411
J 1
(-3125 4475);
DISPLAY 0.617021 (-3125 4475);
PAINT SKYBLUE (-3125 4475);
DISPLAY INVISIBLE (-3125 4475);
FORCEPROP 1 LAST PATH I20
J 0
(-3125 4600);
PAINT GREEN (-3125 4600);
DISPLAY INVISIBLE (-3125 4600);
FORCEADD GND..1
(-2450 575);
FORCEPROP 3 LASTPIN (-2450 625) SIG_NAME GND\g
J 0
(-2440 635);
DISPLAY 0.659574 (-2440 635);
PAINT MONO (-2440 635);
DISPLAY INVISIBLE (-2440 635);
FORCEPROP 1 LAST PATH I23
J 0
(-2375 575);
DISPLAY 0.872340 (-2375 575);
PAINT AQUA (-2375 575);
DISPLAY INVISIBLE (-2375 575);
FORCEPROP 2 LAST CDS_LIB mstr_symbols
J 0
(-2450 575);
PAINT ORANGE (-2450 575);
DISPLAY INVISIBLE (-2450 575);
FORCEPROP 1 LAST VOLTAGE 0
J 0
(-2450 575);
PAINT SKYBLUE (-2450 575);
DISPLAY INVISIBLE (-2450 575);
FORCEPROP 1 LAST SIZE 1B
J 0
(-2375 525);
DISPLAY 1.723404 (-2375 525);
PAINT GREEN (-2375 525);
DISPLAY INVISIBLE (-2375 525);
FORCEPROP 2 LAST BOM_COST PROC_VRD_VCCIN_CPU0
J 0
(-2825 650);
DISPLAY 1.446809 (-2825 650);
PAINT MONO (-2825 650);
DISPLAY INVISIBLE (-2825 650);
FORCEPROP 2 LAST ROOM PVCCIN_CPU1_PWR_VR
J 0
(-3000 650);
DISPLAY 1.936170 (-3000 650);
PAINT ORANGE (-3000 650);
DISPLAY INVISIBLE (-3000 650);
FORCEPROP 1 LAST BODY_TYPE PLUMBING
J 0
(-2495 532);
DISPLAY 0.340426 (-2495 532);
PAINT GREEN (-2495 532);
DISPLAY INVISIBLE (-2495 532);
FORCEPROP 1 LAST HDL_POWER GND
J 0
(-2450 725);
DISPLAY 1.723404 (-2450 725);
PAINT GREEN (-2450 725);
DISPLAY INVISIBLE (-2450 725);
FORCEADD VCC_CORE..1
(-6550 4525);
FORCEPROP 3 LASTPIN (-6550 4475) SIG_NAME VR_FET_SW_P12V_STBY_PVCCIN_CPU1\g
J 0
(-6540 4485);
DISPLAY 0.659574 (-6540 4485);
PAINT MONO (-6540 4485);
DISPLAY INVISIBLE (-6540 4485);
FORCEPROP 1 LAST HDL_POWER VR_FET_SW_P12V_STBY_PVCCIN_CPU1
J 1
(-6475 4575);
DISPLAY 0.617021 (-6475 4575);
PAINT GREEN (-6475 4575);
FORCEPROP 2 LAST CDS_LIB mstr_symbols
J 0
(-6550 4525);
DISPLAY 1.936170 (-6550 4525);
PAINT ORANGE (-6550 4525);
DISPLAY INVISIBLE (-6550 4525);
FORCEPROP 1 LAST PATH I27
J 0
(-6500 4550);
DISPLAY 0.872340 (-6500 4550);
PAINT AQUA (-6500 4550);
DISPLAY INVISIBLE (-6500 4550);
FORCEADD CAP..1
(-4725 4150);
FORCEPROP 1 LAST LOCATION C1E7
J 0
(-4675 4250);
DISPLAY 0.617021 (-4675 4250);
PAINT AQUA (-4675 4250);
FORCEPROP 1 LAST VALUE 0.22UF
J 0
(-4675 4200);
DISPLAY 0.617021 (-4675 4200);
PAINT SKYBLUE (-4675 4200);
FORCEPROP 1 LAST VOLTAGE 16V
J 0
(-4675 4150);
DISPLAY 0.617021 (-4675 4150);
PAINT SKYBLUE (-4675 4150);
FORCEPROP 1 LAST TOLERANCE 10%
J 0
(-4675 4100);
DISPLAY 0.617021 (-4675 4100);
PAINT SKYBLUE (-4675 4100);
FORCEPROP 1 LAST PACK_TYPE 0402
J 0
(-4500 4150);
DISPLAY 0.617021 (-4500 4150);
PAINT SKYBLUE (-4500 4150);
FORCEPROP 1 LAST PART_NUMBER A36096-155
J 0
(-4500 4200);
DISPLAY 0.617021 (-4500 4200);
PAINT BLUE (-4500 4200);
FORCEPROP 1 LASTPIN (-4725 4250) $PN 1
J 0
(-4715 4230);
DISPLAY 0.617021 (-4715 4230);
PAINT ORANGE (-4715 4230);
FORCEPROP 1 LAST MATERIAL X7R
J 0
(-4500 4250);
DISPLAY 0.617021 (-4500 4250);
PAINT SKYBLUE (-4500 4250);
FORCEPROP 1 LASTPIN (-4725 4050) $PN 2
J 0
(-4715 4030);
DISPLAY 0.617021 (-4715 4030);
PAINT ORANGE (-4715 4030);
FORCEPROP 2 LAST CDS_LIB mstr_discrete
J 0
(-4725 4150);
PAINT ORANGE (-4725 4150);
DISPLAY INVISIBLE (-4725 4150);
FORCEPROP 2 LAST ROOM PVCCIN_CPU1_PWR_VR
J 0
(-4675 4300);
DISPLAY 1.361702 (-4675 4300);
PAINT ORANGE (-4675 4300);
DISPLAY INVISIBLE (-4675 4300);
FORCEPROP 1 LAST PATH I28
J 0
(-4675 4300);
DISPLAY 0.978723 (-4675 4300);
PAINT WHITE (-4675 4300);
DISPLAY INVISIBLE (-4675 4300);
FORCEPROP 2 LAST CDS_LOCATION C1E7
J 0
(-4675 4250);
DISPLAY 0.617021 (-4675 4250);
PAINT AQUA (-4675 4250);
DISPLAY INVISIBLE (-4675 4250);
FORCEPROP 2 LAST SEC 1
J 0
(-4675 4350);
DISPLAY 0.680851 (-4675 4350);
PAINT MONO (-4675 4350);
DISPLAY INVISIBLE (-4675 4350);
FORCEPROP 2 LAST SEC_TYPE 0402
J 0
(-4675 4350);
DISPLAY 1.021277 (-4675 4350);
PAINT ORANGE (-4675 4350);
DISPLAY INVISIBLE (-4675 4350);
FORCEADD OFFPAGE..2
(-1550 4100);
FORCEPROP 2 LAST $XR3 206 
J 0
(-1001 4100);
DISPLAY 0.638298 (-1001 4100);
PAINT MONO (-1001 4100);
FORCEPROP 2 LAST $XR2 209 
J 0
(-1121 4100);
DISPLAY 0.638298 (-1121 4100);
PAINT MONO (-1121 4100);
FORCEPROP 2 LAST $XR1 208 
J 0
(-1241 4100);
DISPLAY 0.638298 (-1241 4100);
PAINT MONO (-1241 4100);
FORCEPROP 2 LAST $XR0 207 
J 0
(-1361 4100);
DISPLAY 0.638298 (-1361 4100);
PAINT MONO (-1361 4100);
FORCEPROP 2 LAST ROOM PVCCIN_CPU1_PWR_VR
J 0
(-1950 4175);
DISPLAY 1.936170 (-1950 4175);
PAINT ORANGE (-1950 4175);
DISPLAY INVISIBLE (-1950 4175);
FORCEPROP 2 LAST CDS_LIB mstr_standard
J 0
(-1550 4100);
PAINT ORANGE (-1550 4100);
DISPLAY INVISIBLE (-1550 4100);
FORCEPROP 2 LAST BOM_COST PROC_VRD_VCCIN_CPU0
J 0
(-1350 4150);
DISPLAY 1.446809 (-1350 4150);
PAINT MONO (-1350 4150);
DISPLAY INVISIBLE (-1350 4150);
FORCEPROP 2 LAST PATH I3
J 0
(-1120 4150);
DISPLAY 1.021277 (-1120 4150);
PAINT ORANGE (-1120 4150);
DISPLAY INVISIBLE (-1120 4150);
FORCEPROP 1 LAST OFFPAGE TRUE
J 0
(-1225 3975);
DISPLAY 1.723404 (-1225 3975);
PAINT GREEN (-1225 3975);
DISPLAY INVISIBLE (-1225 3975);
FORCEPROP 1 LAST COMMENT_BODY TRUE
J 0
(-1595 4005);
DISPLAY 1.723404 (-1595 4005);
PAINT GREEN (-1595 4005);
DISPLAY INVISIBLE (-1595 4005);
FORCEADD CAP..1
R 2
(-5675 3500);
FORCEPROP 1 LAST PART_NUMBER A36096-104
J 2
(-5725 3350);
DISPLAY 0.617021 (-5725 3350);
PAINT BLUE (-5725 3350);
FORCEPROP 1 LAST MATERIAL X7R
J 2
(-5725 3400);
DISPLAY 0.617021 (-5725 3400);
PAINT SKYBLUE (-5725 3400);
FORCEPROP 1 LAST TOLERANCE 10%
J 2
(-5725 3450);
DISPLAY 0.617021 (-5725 3450);
PAINT SKYBLUE (-5725 3450);
FORCEPROP 1 LAST VOLTAGE 16V
J 2
(-5725 3500);
DISPLAY 0.617021 (-5725 3500);
PAINT SKYBLUE (-5725 3500);
FORCEPROP 1 LAST VALUE 0.220UF
J 2
(-5725 3550);
DISPLAY 0.617021 (-5725 3550);
PAINT SKYBLUE (-5725 3550);
FORCEPROP 1 LASTPIN (-5675 3400) $PN 2
J 2
(-5685 3380);
DISPLAY 0.617021 (-5685 3380);
PAINT ORANGE (-5685 3380);
FORCEPROP 1 LAST PACK_TYPE 0402
J 2
(-5725 3300);
DISPLAY 0.617021 (-5725 3300);
PAINT SKYBLUE (-5725 3300);
FORCEPROP 1 LAST LOCATION C1E11
J 2
(-5725 3600);
DISPLAY 0.617021 (-5725 3600);
PAINT AQUA (-5725 3600);
FORCEPROP 1 LASTPIN (-5675 3600) $PN 1
J 2
(-5685 3580);
DISPLAY 0.617021 (-5685 3580);
PAINT ORANGE (-5685 3580);
FORCEPROP 2 LAST SEC 1
J 0
(-5725 3700);
PAINT MONO (-5725 3700);
DISPLAY INVISIBLE (-5725 3700);
FORCEPROP 0 LAST SPOF TRUE
J 0
(-5725 3700);
DISPLAY 1.021277 (-5725 3700);
PAINT ORANGE (-5725 3700);
DISPLAY INVISIBLE (-5725 3700);
FORCEPROP 2 LAST SEC_TYPE 0402
J 0
(-5725 3700);
DISPLAY 1.021277 (-5725 3700);
PAINT ORANGE (-5725 3700);
DISPLAY INVISIBLE (-5725 3700);
FORCEPROP 2 LAST ROOM PVCCIN_CPU1_PWR_VR
J 0
(-5750 3650);
DISPLAY 1.361702 (-5750 3650);
PAINT ORANGE (-5750 3650);
DISPLAY INVISIBLE (-5750 3650);
FORCEPROP 1 LAST PATH I30
J 2
(-5725 3650);
DISPLAY 0.978723 (-5725 3650);
PAINT WHITE (-5725 3650);
DISPLAY INVISIBLE (-5725 3650);
FORCEPROP 2 LAST NO_XNET_CONNECTION 1
J 0
(-5725 3700);
PAINT MONO (-5725 3700);
DISPLAY INVISIBLE (-5725 3700);
FORCEPROP 2 LAST CDS_LOCATION C1E11
J 2
(-5725 3600);
DISPLAY 0.617021 (-5725 3600);
PAINT AQUA (-5725 3600);
DISPLAY INVISIBLE (-5725 3600);
FORCEPROP 2 LAST CDS_LIB mstr_discrete
J 0
(-5675 3500);
PAINT ORANGE (-5675 3500);
DISPLAY INVISIBLE (-5675 3500);
FORCEADD CAP..1
(-5550 4100);
FORCEPROP 1 LAST MATERIAL X6S
J 0
(-5500 4000);
DISPLAY 0.617021 (-5500 4000);
PAINT SKYBLUE (-5500 4000);
FORCEPROP 1 LAST PART_NUMBER D97712-011
J 0
(-5500 3950);
DISPLAY 0.617021 (-5500 3950);
PAINT BLUE (-5500 3950);
FORCEPROP 1 LAST PACK_TYPE 0402
J 0
(-5500 3900);
DISPLAY 0.617021 (-5500 3900);
PAINT SKYBLUE (-5500 3900);
FORCEPROP 1 LAST TOLERANCE 10%
J 0
(-5500 4050);
DISPLAY 0.617021 (-5500 4050);
PAINT SKYBLUE (-5500 4050);
FORCEPROP 1 LAST VOLTAGE 16V
J 0
(-5500 4100);
DISPLAY 0.617021 (-5500 4100);
PAINT SKYBLUE (-5500 4100);
FORCEPROP 1 LAST VALUE 1.0UF
J 0
(-5500 4150);
DISPLAY 0.617021 (-5500 4150);
PAINT SKYBLUE (-5500 4150);
FORCEPROP 1 LASTPIN (-5550 4200) $PN 1
J 0
(-5540 4180);
DISPLAY 0.617021 (-5540 4180);
PAINT ORANGE (-5540 4180);
FORCEPROP 1 LASTPIN (-5550 4000) $PN 2
J 0
(-5540 3980);
DISPLAY 0.617021 (-5540 3980);
PAINT ORANGE (-5540 3980);
FORCEPROP 1 LAST LOCATION C1E8
J 0
(-5500 4200);
DISPLAY 0.617021 (-5500 4200);
PAINT AQUA (-5500 4200);
FORCEPROP 2 LAST SEC 1
J 0
(-5500 4300);
DISPLAY 0.680851 (-5500 4300);
PAINT MONO (-5500 4300);
DISPLAY INVISIBLE (-5500 4300);
FORCEPROP 2 LAST SEC_TYPE 0402
J 0
(-5500 4300);
DISPLAY 1.021277 (-5500 4300);
PAINT ORANGE (-5500 4300);
DISPLAY INVISIBLE (-5500 4300);
FORCEPROP 2 LAST CDS_LOCATION C1E8
J 0
(-5500 4200);
DISPLAY 0.617021 (-5500 4200);
PAINT AQUA (-5500 4200);
DISPLAY INVISIBLE (-5500 4200);
FORCEPROP 1 LAST PATH I32
J 0
(-5500 4250);
DISPLAY 0.978723 (-5500 4250);
PAINT WHITE (-5500 4250);
DISPLAY INVISIBLE (-5500 4250);
FORCEPROP 2 LAST ROOM PVCCIN_CPU1_PWR_VR
J 0
(-5500 4250);
DISPLAY 1.361702 (-5500 4250);
PAINT ORANGE (-5500 4250);
DISPLAY INVISIBLE (-5500 4250);
FORCEPROP 2 LAST CDS_LIB mstr_discrete
J 0
(-5550 4100);
PAINT ORANGE (-5550 4100);
DISPLAY INVISIBLE (-5550 4100);
FORCEADD CAP_A..1
(-5850 4125);
FORCEPROP 1 LAST PACK_TYPE 0402V
J 0
(-5800 3925);
DISPLAY 0.617021 (-5800 3925);
PAINT SKYBLUE (-5800 3925);
FORCEPROP 1 LAST PART_NUMBER A36096-030
J 0
(-5800 3975);
DISPLAY 0.617021 (-5800 3975);
PAINT BLUE (-5800 3975);
FORCEPROP 1 LAST MATERIAL X7R
J 0
(-5800 4025);
DISPLAY 0.617021 (-5800 4025);
PAINT SKYBLUE (-5800 4025);
FORCEPROP 1 LAST TOLERANCE 10%
J 0
(-5800 4075);
DISPLAY 0.617021 (-5800 4075);
PAINT SKYBLUE (-5800 4075);
FORCEPROP 1 LAST VOLTAGE 16V
J 0
(-5800 4125);
DISPLAY 0.617021 (-5800 4125);
PAINT SKYBLUE (-5800 4125);
FORCEPROP 1 LAST VALUE 0.1UF
J 0
(-5800 4175);
DISPLAY 0.617021 (-5800 4175);
PAINT SKYBLUE (-5800 4175);
FORCEPROP 1 LAST LOCATION C1E14
J 0
(-5800 4225);
DISPLAY 0.617021 (-5800 4225);
PAINT AQUA (-5800 4225);
FORCEPROP 1 LASTPIN (-5850 4225) $PN 1
J 0
(-5840 4205);
DISPLAY 0.617021 (-5840 4205);
PAINT ORANGE (-5840 4205);
FORCEPROP 1 LASTPIN (-5850 4025) $PN 2
J 0
(-5840 4005);
DISPLAY 0.617021 (-5840 4005);
PAINT ORANGE (-5840 4005);
FORCEPROP 2 LAST SEC 1
J 0
(-5800 4325);
DISPLAY 0.680851 (-5800 4325);
PAINT MONO (-5800 4325);
DISPLAY INVISIBLE (-5800 4325);
FORCEPROP 2 LAST SEC_TYPE 0402V
J 0
(-5800 4325);
DISPLAY 1.021277 (-5800 4325);
PAINT ORANGE (-5800 4325);
DISPLAY INVISIBLE (-5800 4325);
FORCEPROP 2 LAST CDS_SEC 1
J 0
(-5800 4275);
PAINT ORANGE (-5800 4275);
DISPLAY INVISIBLE (-5800 4275);
FORCEPROP 2 LAST ROOM PVCCIN_CPU1_PWR_VR
J 0
(-5800 4275);
DISPLAY 1.361702 (-5800 4275);
PAINT ORANGE (-5800 4275);
DISPLAY INVISIBLE (-5800 4275);
FORCEPROP 1 LAST PATH I33
J 0
(-5800 4275);
DISPLAY 0.978723 (-5800 4275);
PAINT WHITE (-5800 4275);
DISPLAY INVISIBLE (-5800 4275);
FORCEPROP 2 LAST CDS_LOCATION C1E14
J 0
(-5800 4225);
DISPLAY 0.617021 (-5800 4225);
PAINT AQUA (-5800 4225);
DISPLAY INVISIBLE (-5800 4225);
FORCEPROP 2 LAST CDS_LIB dev_discrete
J 0
(-5850 4125);
PAINT ORANGE (-5850 4125);
DISPLAY INVISIBLE (-5850 4125);
FORCEADD CAP..1
(-6150 4125);
FORCEPROP 1 LAST PACK_TYPE 0402
J 0
(-6100 3925);
DISPLAY 0.617021 (-6100 3925);
PAINT SKYBLUE (-6100 3925);
FORCEPROP 1 LAST PART_NUMBER D97712-011
J 0
(-6100 3975);
DISPLAY 0.617021 (-6100 3975);
PAINT BLUE (-6100 3975);
FORCEPROP 1 LAST MATERIAL X6S
J 0
(-6100 4025);
DISPLAY 0.617021 (-6100 4025);
PAINT SKYBLUE (-6100 4025);
FORCEPROP 1 LAST TOLERANCE 10%
J 0
(-6100 4075);
DISPLAY 0.617021 (-6100 4075);
PAINT SKYBLUE (-6100 4075);
FORCEPROP 1 LAST VOLTAGE 16V
J 0
(-6100 4125);
DISPLAY 0.617021 (-6100 4125);
PAINT SKYBLUE (-6100 4125);
FORCEPROP 1 LAST VALUE 1.0UF
J 0
(-6100 4175);
DISPLAY 0.617021 (-6100 4175);
PAINT SKYBLUE (-6100 4175);
FORCEPROP 1 LASTPIN (-6150 4025) $PN 2
J 0
(-6140 4005);
DISPLAY 0.617021 (-6140 4005);
PAINT ORANGE (-6140 4005);
FORCEPROP 1 LASTPIN (-6150 4225) $PN 1
J 0
(-6140 4205);
DISPLAY 0.617021 (-6140 4205);
PAINT ORANGE (-6140 4205);
FORCEPROP 1 LAST LOCATION C1E13
J 0
(-6100 4225);
DISPLAY 0.617021 (-6100 4225);
PAINT AQUA (-6100 4225);
FORCEPROP 2 LAST CDS_LIB mstr_discrete
J 0
(-6150 4125);
PAINT ORANGE (-6150 4125);
DISPLAY INVISIBLE (-6150 4125);
FORCEPROP 2 LAST ROOM PVCCIN_CPU1_PWR_VR
J 0
(-6100 4275);
DISPLAY 1.361702 (-6100 4275);
PAINT ORANGE (-6100 4275);
DISPLAY INVISIBLE (-6100 4275);
FORCEPROP 1 LAST PATH I34
J 0
(-6100 4275);
DISPLAY 0.978723 (-6100 4275);
PAINT WHITE (-6100 4275);
DISPLAY INVISIBLE (-6100 4275);
FORCEPROP 2 LAST CDS_LOCATION C1E13
J 0
(-6100 4225);
DISPLAY 0.617021 (-6100 4225);
PAINT AQUA (-6100 4225);
DISPLAY INVISIBLE (-6100 4225);
FORCEPROP 2 LAST SEC 1
J 0
(-6100 4325);
DISPLAY 0.680851 (-6100 4325);
PAINT MONO (-6100 4325);
DISPLAY INVISIBLE (-6100 4325);
FORCEPROP 2 LAST SEC_TYPE 0402
J 0
(-6100 4325);
DISPLAY 1.021277 (-6100 4325);
PAINT ORANGE (-6100 4325);
DISPLAY INVISIBLE (-6100 4325);
FORCEADD CAP..1
(-4600 1575);
FORCEPROP 1 LAST PART_NUMBER A36096-155
J 0
(-4400 1625);
DISPLAY 0.617021 (-4400 1625);
PAINT BLUE (-4400 1625);
FORCEPROP 1 LAST MATERIAL X7R
J 0
(-4400 1675);
DISPLAY 0.617021 (-4400 1675);
PAINT SKYBLUE (-4400 1675);
FORCEPROP 1 LASTPIN (-4600 1475) $PN 2
J 0
(-4590 1455);
DISPLAY 0.617021 (-4590 1455);
PAINT ORANGE (-4590 1455);
FORCEPROP 1 LAST VOLTAGE 16V
J 0
(-4550 1575);
DISPLAY 0.617021 (-4550 1575);
PAINT SKYBLUE (-4550 1575);
FORCEPROP 1 LASTPIN (-4600 1675) $PN 1
J 0
(-4590 1655);
DISPLAY 0.617021 (-4590 1655);
PAINT ORANGE (-4590 1655);
FORCEPROP 1 LAST LOCATION C1E25
J 0
(-4550 1675);
DISPLAY 0.617021 (-4550 1675);
PAINT AQUA (-4550 1675);
FORCEPROP 1 LAST PACK_TYPE 0402
J 0
(-4400 1575);
DISPLAY 0.617021 (-4400 1575);
PAINT SKYBLUE (-4400 1575);
FORCEPROP 1 LAST TOLERANCE 10%
J 0
(-4550 1525);
DISPLAY 0.617021 (-4550 1525);
PAINT SKYBLUE (-4550 1525);
FORCEPROP 1 LAST VALUE 0.22UF
J 0
(-4550 1625);
DISPLAY 0.617021 (-4550 1625);
PAINT SKYBLUE (-4550 1625);
FORCEPROP 2 LAST SEC_TYPE 0402
J 0
(-4550 1775);
DISPLAY 1.021277 (-4550 1775);
PAINT ORANGE (-4550 1775);
DISPLAY INVISIBLE (-4550 1775);
FORCEPROP 1 LAST PATH I36
J 0
(-4550 1725);
DISPLAY 0.978723 (-4550 1725);
PAINT WHITE (-4550 1725);
DISPLAY INVISIBLE (-4550 1725);
FORCEPROP 2 LAST SEC 1
J 0
(-4550 1775);
DISPLAY 0.680851 (-4550 1775);
PAINT MONO (-4550 1775);
DISPLAY INVISIBLE (-4550 1775);
FORCEPROP 2 LAST CDS_LIB mstr_discrete
J 0
(-4600 1575);
PAINT ORANGE (-4600 1575);
DISPLAY INVISIBLE (-4600 1575);
FORCEPROP 2 LAST ROOM PVCCIN_CPU1_PWR_VR
J 0
(-4550 1725);
DISPLAY 1.361702 (-4550 1725);
PAINT ORANGE (-4550 1725);
DISPLAY INVISIBLE (-4550 1725);
FORCEADD CAP..1
R 2
(-5550 875);
FORCEPROP 1 LAST VOLTAGE 16V
J 2
(-5600 875);
DISPLAY 0.617021 (-5600 875);
PAINT SKYBLUE (-5600 875);
FORCEPROP 1 LAST VALUE 0.220UF
J 2
(-5600 925);
DISPLAY 0.617021 (-5600 925);
PAINT SKYBLUE (-5600 925);
FORCEPROP 1 LASTPIN (-5550 775) $PN 2
J 2
(-5560 755);
DISPLAY 0.617021 (-5560 755);
PAINT ORANGE (-5560 755);
FORCEPROP 1 LASTPIN (-5550 975) $PN 1
J 2
(-5560 955);
DISPLAY 0.617021 (-5560 955);
PAINT ORANGE (-5560 955);
FORCEPROP 1 LAST LOCATION C1D36
J 2
(-5600 975);
DISPLAY 0.617021 (-5600 975);
PAINT AQUA (-5600 975);
FORCEPROP 1 LAST TOLERANCE 10%
J 2
(-5600 825);
DISPLAY 0.617021 (-5600 825);
PAINT SKYBLUE (-5600 825);
FORCEPROP 1 LAST MATERIAL X7R
J 2
(-5600 775);
DISPLAY 0.617021 (-5600 775);
PAINT SKYBLUE (-5600 775);
FORCEPROP 1 LAST PART_NUMBER A36096-104
J 2
(-5600 725);
DISPLAY 0.617021 (-5600 725);
PAINT BLUE (-5600 725);
FORCEPROP 1 LAST PACK_TYPE 0402
J 2
(-5600 675);
DISPLAY 0.617021 (-5600 675);
PAINT SKYBLUE (-5600 675);
FORCEPROP 2 LAST CDS_LIB mstr_discrete
J 0
(-5550 875);
PAINT ORANGE (-5550 875);
DISPLAY INVISIBLE (-5550 875);
FORCEPROP 2 LAST ROOM PVCCIN_CPU1_PWR_VR
J 0
(-5600 1025);
DISPLAY 1.361702 (-5600 1025);
PAINT ORANGE (-5600 1025);
DISPLAY INVISIBLE (-5600 1025);
FORCEPROP 1 LAST PATH I38
J 2
(-5600 1025);
DISPLAY 0.978723 (-5600 1025);
PAINT WHITE (-5600 1025);
DISPLAY INVISIBLE (-5600 1025);
FORCEPROP 2 LAST NO_XNET_CONNECTION 1
J 0
(-5600 1075);
PAINT MONO (-5600 1075);
DISPLAY INVISIBLE (-5600 1075);
FORCEPROP 2 LAST SEC 1
J 0
(-5600 1075);
DISPLAY 0.680851 (-5600 1075);
PAINT MONO (-5600 1075);
DISPLAY INVISIBLE (-5600 1075);
FORCEPROP 0 LAST SPOF TRUE
J 0
(-5600 1075);
DISPLAY 1.021277 (-5600 1075);
PAINT ORANGE (-5600 1075);
DISPLAY INVISIBLE (-5600 1075);
FORCEPROP 2 LAST SEC_TYPE 0402
J 0
(-5600 1075);
DISPLAY 1.021277 (-5600 1075);
PAINT ORANGE (-5600 1075);
DISPLAY INVISIBLE (-5600 1075);
FORCEADD CAP..1
(-5450 1525);
FORCEPROP 1 LASTPIN (-5450 1625) $PN 1
J 0
(-5440 1605);
DISPLAY 0.617021 (-5440 1605);
PAINT ORANGE (-5440 1605);
FORCEPROP 1 LAST TOLERANCE 10%
J 0
(-5400 1475);
DISPLAY 0.617021 (-5400 1475);
PAINT SKYBLUE (-5400 1475);
FORCEPROP 1 LAST LOCATION C1E24
J 0
(-5400 1625);
DISPLAY 0.617021 (-5400 1625);
PAINT AQUA (-5400 1625);
FORCEPROP 1 LASTPIN (-5450 1425) $PN 2
J 0
(-5440 1405);
DISPLAY 0.617021 (-5440 1405);
PAINT ORANGE (-5440 1405);
FORCEPROP 1 LAST VALUE 1.0UF
J 0
(-5400 1575);
DISPLAY 0.617021 (-5400 1575);
PAINT SKYBLUE (-5400 1575);
FORCEPROP 1 LAST VOLTAGE 16V
J 0
(-5400 1525);
DISPLAY 0.617021 (-5400 1525);
PAINT SKYBLUE (-5400 1525);
FORCEPROP 1 LAST MATERIAL X6S
J 0
(-5400 1425);
DISPLAY 0.617021 (-5400 1425);
PAINT SKYBLUE (-5400 1425);
FORCEPROP 1 LAST PART_NUMBER D97712-011
J 0
(-5400 1375);
DISPLAY 0.617021 (-5400 1375);
PAINT BLUE (-5400 1375);
FORCEPROP 1 LAST PACK_TYPE 0402
J 0
(-5400 1325);
DISPLAY 0.617021 (-5400 1325);
PAINT SKYBLUE (-5400 1325);
FORCEPROP 2 LAST CDS_LIB mstr_discrete
J 0
(-5450 1525);
PAINT ORANGE (-5450 1525);
DISPLAY INVISIBLE (-5450 1525);
FORCEPROP 2 LAST ROOM PVCCIN_CPU1_PWR_VR
J 0
(-5400 1675);
DISPLAY 1.361702 (-5400 1675);
PAINT ORANGE (-5400 1675);
DISPLAY INVISIBLE (-5400 1675);
FORCEPROP 1 LAST PATH I40
J 0
(-5400 1675);
DISPLAY 0.978723 (-5400 1675);
PAINT WHITE (-5400 1675);
DISPLAY INVISIBLE (-5400 1675);
FORCEPROP 2 LAST SEC_TYPE 0402
J 0
(-5400 1725);
DISPLAY 1.021277 (-5400 1725);
PAINT ORANGE (-5400 1725);
DISPLAY INVISIBLE (-5400 1725);
FORCEPROP 2 LAST SEC 1
J 0
(-5400 1725);
DISPLAY 0.680851 (-5400 1725);
PAINT MONO (-5400 1725);
DISPLAY INVISIBLE (-5400 1725);
FORCEADD CAP_A..1
(-5725 1525);
FORCEPROP 1 LAST LOCATION C1D34
J 0
(-5675 1625);
DISPLAY 0.617021 (-5675 1625);
PAINT AQUA (-5675 1625);
FORCEPROP 1 LASTPIN (-5725 1625) $PN 1
J 0
(-5715 1605);
DISPLAY 0.617021 (-5715 1605);
PAINT ORANGE (-5715 1605);
FORCEPROP 1 LAST VALUE 0.1UF
J 0
(-5675 1575);
DISPLAY 0.617021 (-5675 1575);
PAINT SKYBLUE (-5675 1575);
FORCEPROP 1 LASTPIN (-5725 1425) $PN 2
J 0
(-5715 1405);
DISPLAY 0.617021 (-5715 1405);
PAINT ORANGE (-5715 1405);
FORCEPROP 1 LAST VOLTAGE 16V
J 0
(-5675 1525);
DISPLAY 0.617021 (-5675 1525);
PAINT SKYBLUE (-5675 1525);
FORCEPROP 1 LAST TOLERANCE 10%
J 0
(-5675 1475);
DISPLAY 0.617021 (-5675 1475);
PAINT SKYBLUE (-5675 1475);
FORCEPROP 1 LAST MATERIAL X7R
J 0
(-5675 1425);
DISPLAY 0.617021 (-5675 1425);
PAINT SKYBLUE (-5675 1425);
FORCEPROP 1 LAST PART_NUMBER A36096-030
J 0
(-5675 1375);
DISPLAY 0.617021 (-5675 1375);
PAINT BLUE (-5675 1375);
FORCEPROP 1 LAST PACK_TYPE 0402V
J 0
(-5675 1325);
DISPLAY 0.617021 (-5675 1325);
PAINT SKYBLUE (-5675 1325);
FORCEPROP 2 LAST CDS_LIB dev_discrete
J 0
(-5725 1525);
PAINT ORANGE (-5725 1525);
DISPLAY INVISIBLE (-5725 1525);
FORCEPROP 1 LAST PATH I41
J 0
(-5675 1675);
DISPLAY 0.978723 (-5675 1675);
PAINT WHITE (-5675 1675);
DISPLAY INVISIBLE (-5675 1675);
FORCEPROP 2 LAST ROOM PVCCIN_CPU1_PWR_VR
J 0
(-5675 1675);
DISPLAY 1.361702 (-5675 1675);
PAINT ORANGE (-5675 1675);
DISPLAY INVISIBLE (-5675 1675);
FORCEPROP 2 LAST CDS_SEC 1
J 0
(-5675 1675);
PAINT ORANGE (-5675 1675);
DISPLAY INVISIBLE (-5675 1675);
FORCEPROP 2 LAST SEC 1
J 0
(-5675 1725);
DISPLAY 0.680851 (-5675 1725);
PAINT MONO (-5675 1725);
DISPLAY INVISIBLE (-5675 1725);
FORCEPROP 2 LAST SEC_TYPE 0402V
J 0
(-5675 1725);
DISPLAY 1.021277 (-5675 1725);
PAINT ORANGE (-5675 1725);
DISPLAY INVISIBLE (-5675 1725);
FORCEADD CAP..1
(-6025 1550);
FORCEPROP 1 LAST LOCATION C1D35
J 0
(-5975 1650);
DISPLAY 0.617021 (-5975 1650);
PAINT AQUA (-5975 1650);
FORCEPROP 1 LASTPIN (-6025 1450) $PN 2
J 0
(-6015 1430);
DISPLAY 0.617021 (-6015 1430);
PAINT ORANGE (-6015 1430);
FORCEPROP 1 LASTPIN (-6025 1650) $PN 1
J 0
(-6015 1630);
DISPLAY 0.617021 (-6015 1630);
PAINT ORANGE (-6015 1630);
FORCEPROP 1 LAST VALUE 1.0UF
J 0
(-5975 1600);
DISPLAY 0.617021 (-5975 1600);
PAINT SKYBLUE (-5975 1600);
FORCEPROP 1 LAST VOLTAGE 16V
J 0
(-5975 1550);
DISPLAY 0.617021 (-5975 1550);
PAINT SKYBLUE (-5975 1550);
FORCEPROP 1 LAST TOLERANCE 10%
J 0
(-5975 1500);
DISPLAY 0.617021 (-5975 1500);
PAINT SKYBLUE (-5975 1500);
FORCEPROP 1 LAST MATERIAL X6S
J 0
(-5975 1450);
DISPLAY 0.617021 (-5975 1450);
PAINT SKYBLUE (-5975 1450);
FORCEPROP 1 LAST PART_NUMBER D97712-011
J 0
(-5975 1400);
DISPLAY 0.617021 (-5975 1400);
PAINT BLUE (-5975 1400);
FORCEPROP 1 LAST PACK_TYPE 0402
J 0
(-5975 1350);
DISPLAY 0.617021 (-5975 1350);
PAINT SKYBLUE (-5975 1350);
FORCEPROP 2 LAST CDS_LIB mstr_discrete
J 0
(-6025 1550);
PAINT ORANGE (-6025 1550);
DISPLAY INVISIBLE (-6025 1550);
FORCEPROP 2 LAST SEC_TYPE 0402
J 0
(-5975 1750);
DISPLAY 1.021277 (-5975 1750);
PAINT ORANGE (-5975 1750);
DISPLAY INVISIBLE (-5975 1750);
FORCEPROP 2 LAST SEC 1
J 0
(-5975 1750);
DISPLAY 0.680851 (-5975 1750);
PAINT MONO (-5975 1750);
DISPLAY INVISIBLE (-5975 1750);
FORCEPROP 1 LAST PATH I42
J 0
(-5975 1700);
DISPLAY 0.978723 (-5975 1700);
PAINT WHITE (-5975 1700);
DISPLAY INVISIBLE (-5975 1700);
FORCEPROP 2 LAST ROOM PVCCIN_CPU1_PWR_VR
J 0
(-5975 1700);
DISPLAY 1.361702 (-5975 1700);
PAINT ORANGE (-5975 1700);
DISPLAY INVISIBLE (-5975 1700);
FORCEADD CAP..1
(-6425 4125);
FORCEPROP 1 LAST LOCATION C9R7
J 0
(-6375 4225);
DISPLAY 0.617021 (-6375 4225);
PAINT AQUA (-6375 4225);
FORCEPROP 1 LAST VALUE 10UF
J 0
(-6375 4175);
DISPLAY 0.617021 (-6375 4175);
PAINT SKYBLUE (-6375 4175);
FORCEPROP 1 LAST TOLERANCE 10%
J 0
(-6375 4075);
DISPLAY 0.617021 (-6375 4075);
PAINT SKYBLUE (-6375 4075);
FORCEPROP 1 LAST MATERIAL X6S
J 0
(-6375 4025);
DISPLAY 0.617021 (-6375 4025);
PAINT SKYBLUE (-6375 4025);
FORCEPROP 1 LAST PART_NUMBER C95333-007
J 0
(-6375 3975);
DISPLAY 0.617021 (-6375 3975);
PAINT BLUE (-6375 3975);
FORCEPROP 1 LASTPIN (-6425 4025) $PN 2
J 0
(-6415 4005);
DISPLAY 0.617021 (-6415 4005);
PAINT ORANGE (-6415 4005);
FORCEPROP 1 LASTPIN (-6425 4225) $PN 1
J 0
(-6415 4205);
DISPLAY 0.617021 (-6415 4205);
PAINT ORANGE (-6415 4205);
FORCEPROP 1 LAST PACK_TYPE 0805
J 0
(-6375 3925);
DISPLAY 0.617021 (-6375 3925);
PAINT SKYBLUE (-6375 3925);
FORCEPROP 1 LAST VOLTAGE 16V
J 0
(-6375 4125);
DISPLAY 0.617021 (-6375 4125);
PAINT SKYBLUE (-6375 4125);
FORCEPROP 2 LAST CDS_LIB mstr_discrete
J 0
(-6425 4125);
PAINT ORANGE (-6425 4125);
DISPLAY INVISIBLE (-6425 4125);
FORCEPROP 2 LAST CDS_LOCATION C9R7
J 0
(-6375 4225);
DISPLAY 0.617021 (-6375 4225);
PAINT AQUA (-6375 4225);
DISPLAY INVISIBLE (-6375 4225);
FORCEPROP 2 LAST ROOM PVCCIN_CPU1_PWR_VR
J 0
(-6375 4275);
DISPLAY 1.361702 (-6375 4275);
PAINT ORANGE (-6375 4275);
DISPLAY INVISIBLE (-6375 4275);
FORCEPROP 1 LAST PATH I43
J 0
(-6375 4275);
DISPLAY 0.978723 (-6375 4275);
PAINT WHITE (-6375 4275);
DISPLAY INVISIBLE (-6375 4275);
FORCEPROP 2 LAST SEC 1
J 0
(-6375 4325);
DISPLAY 0.680851 (-6375 4325);
PAINT MONO (-6375 4325);
DISPLAY INVISIBLE (-6375 4325);
FORCEPROP 2 LAST SEC_TYPE 0805
J 0
(-6375 4325);
DISPLAY 1.021277 (-6375 4325);
PAINT ORANGE (-6375 4325);
DISPLAY INVISIBLE (-6375 4325);
FORCEADD CAP..1
(-6725 4125);
FORCEPROP 1 LASTPIN (-6725 4025) $PN 2
J 0
(-6715 4005);
DISPLAY 0.617021 (-6715 4005);
PAINT ORANGE (-6715 4005);
FORCEPROP 1 LAST MATERIAL X6S
J 0
(-6675 4025);
DISPLAY 0.617021 (-6675 4025);
PAINT SKYBLUE (-6675 4025);
FORCEPROP 1 LAST TOLERANCE 10%
J 0
(-6675 4075);
DISPLAY 0.617021 (-6675 4075);
PAINT SKYBLUE (-6675 4075);
FORCEPROP 1 LASTPIN (-6725 4225) $PN 1
J 0
(-6715 4205);
DISPLAY 0.617021 (-6715 4205);
PAINT ORANGE (-6715 4205);
FORCEPROP 1 LAST VALUE 10UF
J 0
(-6675 4175);
DISPLAY 0.617021 (-6675 4175);
PAINT SKYBLUE (-6675 4175);
FORCEPROP 1 LAST LOCATION C9R10
J 0
(-6675 4225);
DISPLAY 0.617021 (-6675 4225);
PAINT AQUA (-6675 4225);
FORCEPROP 1 LAST VOLTAGE 16V
J 0
(-6675 4125);
DISPLAY 0.617021 (-6675 4125);
PAINT SKYBLUE (-6675 4125);
FORCEPROP 1 LAST PART_NUMBER C95333-007
J 0
(-6675 3975);
DISPLAY 0.617021 (-6675 3975);
PAINT BLUE (-6675 3975);
FORCEPROP 1 LAST PACK_TYPE 0805
J 0
(-6675 3925);
DISPLAY 0.617021 (-6675 3925);
PAINT SKYBLUE (-6675 3925);
FORCEPROP 2 LAST CDS_LIB mstr_discrete
J 0
(-6725 4125);
PAINT ORANGE (-6725 4125);
DISPLAY INVISIBLE (-6725 4125);
FORCEPROP 2 LAST ROOM PVCCIN_CPU1_PWR_VR
J 0
(-6675 4275);
DISPLAY 1.361702 (-6675 4275);
PAINT ORANGE (-6675 4275);
DISPLAY INVISIBLE (-6675 4275);
FORCEPROP 1 LAST PATH I44
J 0
(-6675 4275);
DISPLAY 0.978723 (-6675 4275);
PAINT WHITE (-6675 4275);
DISPLAY INVISIBLE (-6675 4275);
FORCEPROP 2 LAST CDS_LOCATION C9R10
J 0
(-6675 4225);
DISPLAY 0.617021 (-6675 4225);
PAINT AQUA (-6675 4225);
DISPLAY INVISIBLE (-6675 4225);
FORCEPROP 2 LAST SEC 1
J 0
(-6675 4325);
DISPLAY 0.680851 (-6675 4325);
PAINT MONO (-6675 4325);
DISPLAY INVISIBLE (-6675 4325);
FORCEPROP 2 LAST SEC_TYPE 0805
J 0
(-6675 4325);
DISPLAY 1.021277 (-6675 4325);
PAINT ORANGE (-6675 4325);
DISPLAY INVISIBLE (-6675 4325);
FORCEADD OFFPAGE..1
(-6450 3750);
FORCEPROP 2 LASTPIN (-6400 3750) SIG_NAME VR_PVCCIN_CPU1_PWM1
J 0
(-6385 3760);
DISPLAY 0.617021 (-6385 3760);
PAINT ORANGE (-6385 3760);
FORCEPROP 2 LAST $XR0 206 
J 0
(-6732 3750);
DISPLAY 0.638298 (-6732 3750);
PAINT MONO (-6732 3750);
FORCEPROP 2 LAST CDS_LIB mstr_standard
J 0
(-6450 3750);
DISPLAY 1.936170 (-6450 3750);
PAINT ORANGE (-6450 3750);
DISPLAY INVISIBLE (-6450 3750);
FORCEPROP 2 LAST BOM_COST PROC_VRD_VCCIN_CPU0
J 0
(-6700 3800);
DISPLAY 1.446809 (-6700 3800);
PAINT MONO (-6700 3800);
DISPLAY INVISIBLE (-6700 3800);
FORCEPROP 2 LAST PATH I45
J 0
(-6695 3800);
DISPLAY 1.021277 (-6695 3800);
PAINT ORANGE (-6695 3800);
DISPLAY INVISIBLE (-6695 3800);
FORCEPROP 2 LAST ROOM PVCCIN_CPU1_PWR_VR
J 0
(-6850 3825);
DISPLAY 1.936170 (-6850 3825);
PAINT ORANGE (-6850 3825);
DISPLAY INVISIBLE (-6850 3825);
FORCEPROP 1 LAST OFFPAGE TRUE
J 0
(-6125 3625);
DISPLAY 1.680851 (-6125 3625);
PAINT GREEN (-6125 3625);
DISPLAY INVISIBLE (-6125 3625);
FORCEPROP 1 LAST COMMENT_BODY TRUE
J 0
(-6325 3650);
DISPLAY 1.680851 (-6325 3650);
PAINT GREEN (-6325 3650);
DISPLAY INVISIBLE (-6325 3650);
FORCEADD CAP..1
(-7025 4125);
FORCEPROP 1 LAST PACK_TYPE 0805
J 0
(-6975 3925);
DISPLAY 0.617021 (-6975 3925);
PAINT SKYBLUE (-6975 3925);
FORCEPROP 1 LAST MATERIAL X6S
J 0
(-6975 4025);
DISPLAY 0.617021 (-6975 4025);
PAINT SKYBLUE (-6975 4025);
FORCEPROP 1 LAST TOLERANCE 10%
J 0
(-6975 4075);
DISPLAY 0.617021 (-6975 4075);
PAINT SKYBLUE (-6975 4075);
FORCEPROP 1 LASTPIN (-7025 4025) $PN 2
J 0
(-7015 4005);
DISPLAY 0.617021 (-7015 4005);
PAINT ORANGE (-7015 4005);
FORCEPROP 1 LASTPIN (-7025 4225) $PN 1
J 0
(-7015 4205);
DISPLAY 0.617021 (-7015 4205);
PAINT ORANGE (-7015 4205);
FORCEPROP 1 LAST VOLTAGE 16V
J 0
(-6975 4125);
DISPLAY 0.617021 (-6975 4125);
PAINT SKYBLUE (-6975 4125);
FORCEPROP 1 LAST VALUE 10UF
J 0
(-6975 4175);
DISPLAY 0.617021 (-6975 4175);
PAINT SKYBLUE (-6975 4175);
FORCEPROP 1 LAST PART_NUMBER C95333-007
J 0
(-6975 3975);
DISPLAY 0.617021 (-6975 3975);
PAINT BLUE (-6975 3975);
FORCEPROP 1 LAST LOCATION C9R11
J 0
(-6975 4225);
DISPLAY 0.617021 (-6975 4225);
PAINT AQUA (-6975 4225);
FORCEPROP 2 LAST CDS_LIB mstr_discrete
J 0
(-7025 4125);
PAINT ORANGE (-7025 4125);
DISPLAY INVISIBLE (-7025 4125);
FORCEPROP 2 LAST ROOM PVCCIN_CPU1_PWR_VR
J 0
(-6975 4275);
DISPLAY 1.361702 (-6975 4275);
PAINT ORANGE (-6975 4275);
DISPLAY INVISIBLE (-6975 4275);
FORCEPROP 1 LAST PATH I48
J 0
(-6975 4275);
DISPLAY 0.978723 (-6975 4275);
PAINT WHITE (-6975 4275);
DISPLAY INVISIBLE (-6975 4275);
FORCEPROP 2 LAST CDS_LOCATION C9R11
J 0
(-6975 4225);
DISPLAY 0.617021 (-6975 4225);
PAINT AQUA (-6975 4225);
DISPLAY INVISIBLE (-6975 4225);
FORCEPROP 2 LAST SEC 1
J 0
(-6975 4325);
DISPLAY 0.680851 (-6975 4325);
PAINT MONO (-6975 4325);
DISPLAY INVISIBLE (-6975 4325);
FORCEPROP 2 LAST SEC_TYPE 0805
J 0
(-6975 4325);
DISPLAY 1.021277 (-6975 4325);
PAINT ORANGE (-6975 4325);
DISPLAY INVISIBLE (-6975 4325);
FORCEADD GND..1
(-7025 3725);
FORCEPROP 3 LASTPIN (-7025 3775) SIG_NAME GND\g
J 0
(-7015 3785);
DISPLAY 0.659574 (-7015 3785);
PAINT MONO (-7015 3785);
DISPLAY INVISIBLE (-7015 3785);
FORCEPROP 2 LAST ROOM PVCCIN_CPU1_PWR_VR
J 0
(-7575 3800);
DISPLAY 1.936170 (-7575 3800);
PAINT ORANGE (-7575 3800);
DISPLAY INVISIBLE (-7575 3800);
FORCEPROP 2 LAST BOM_COST PROC_VRD_VCCIN_CPU0
J 0
(-7400 3800);
DISPLAY 1.446809 (-7400 3800);
PAINT MONO (-7400 3800);
DISPLAY INVISIBLE (-7400 3800);
FORCEPROP 1 LAST SIZE 1B
J 0
(-6950 3675);
DISPLAY 1.723404 (-6950 3675);
PAINT GREEN (-6950 3675);
DISPLAY INVISIBLE (-6950 3675);
FORCEPROP 2 LAST CDS_LIB mstr_symbols
J 0
(-7025 3725);
DISPLAY 1.936170 (-7025 3725);
PAINT ORANGE (-7025 3725);
DISPLAY INVISIBLE (-7025 3725);
FORCEPROP 1 LAST VOLTAGE 0
J 0
(-7025 3725);
PAINT SKYBLUE (-7025 3725);
DISPLAY INVISIBLE (-7025 3725);
FORCEPROP 1 LAST PATH I49
J 0
(-6950 3725);
DISPLAY 0.872340 (-6950 3725);
PAINT AQUA (-6950 3725);
DISPLAY INVISIBLE (-6950 3725);
FORCEPROP 1 LAST BODY_TYPE PLUMBING
J 0
(-7070 3682);
DISPLAY 0.340426 (-7070 3682);
PAINT GREEN (-7070 3682);
DISPLAY INVISIBLE (-7070 3682);
FORCEPROP 1 LAST HDL_POWER GND
J 0
(-7025 3875);
DISPLAY 1.723404 (-7025 3875);
PAINT GREEN (-7025 3875);
DISPLAY INVISIBLE (-7025 3875);
FORCEADD CAP..1
(-6300 1550);
FORCEPROP 1 LASTPIN (-6300 1450) $PN 2
J 0
(-6290 1430);
DISPLAY 0.617021 (-6290 1430);
PAINT ORANGE (-6290 1430);
FORCEPROP 1 LASTPIN (-6300 1650) $PN 1
J 0
(-6290 1630);
DISPLAY 0.617021 (-6290 1630);
PAINT ORANGE (-6290 1630);
FORCEPROP 1 LAST LOCATION C9P22
J 0
(-6250 1650);
DISPLAY 0.617021 (-6250 1650);
PAINT AQUA (-6250 1650);
FORCEPROP 1 LAST VALUE 10UF
J 0
(-6250 1600);
DISPLAY 0.617021 (-6250 1600);
PAINT SKYBLUE (-6250 1600);
FORCEPROP 1 LAST VOLTAGE 16V
J 0
(-6250 1550);
DISPLAY 0.617021 (-6250 1550);
PAINT SKYBLUE (-6250 1550);
FORCEPROP 1 LAST TOLERANCE 10%
J 0
(-6250 1500);
DISPLAY 0.617021 (-6250 1500);
PAINT SKYBLUE (-6250 1500);
FORCEPROP 1 LAST MATERIAL X6S
J 0
(-6250 1450);
DISPLAY 0.617021 (-6250 1450);
PAINT SKYBLUE (-6250 1450);
FORCEPROP 1 LAST PART_NUMBER C95333-007
J 0
(-6250 1400);
DISPLAY 0.617021 (-6250 1400);
PAINT BLUE (-6250 1400);
FORCEPROP 1 LAST PACK_TYPE 0805
J 0
(-6250 1350);
DISPLAY 0.617021 (-6250 1350);
PAINT SKYBLUE (-6250 1350);
FORCEPROP 2 LAST CDS_LIB mstr_discrete
J 0
(-6300 1550);
PAINT ORANGE (-6300 1550);
DISPLAY INVISIBLE (-6300 1550);
FORCEPROP 2 LAST ROOM PVCCIN_CPU1_PWR_VR
J 0
(-6250 1700);
DISPLAY 1.361702 (-6250 1700);
PAINT ORANGE (-6250 1700);
DISPLAY INVISIBLE (-6250 1700);
FORCEPROP 1 LAST PATH I50
J 0
(-6250 1700);
DISPLAY 0.978723 (-6250 1700);
PAINT WHITE (-6250 1700);
DISPLAY INVISIBLE (-6250 1700);
FORCEPROP 2 LAST CDS_LOCATION C9P22
J 0
(-6250 1650);
DISPLAY 0.617021 (-6250 1650);
PAINT AQUA (-6250 1650);
DISPLAY INVISIBLE (-6250 1650);
FORCEPROP 2 LAST SEC 1
J 0
(-6250 1750);
DISPLAY 0.680851 (-6250 1750);
PAINT MONO (-6250 1750);
DISPLAY INVISIBLE (-6250 1750);
FORCEPROP 2 LAST SEC_TYPE 0805
J 0
(-6250 1750);
DISPLAY 1.021277 (-6250 1750);
PAINT ORANGE (-6250 1750);
DISPLAY INVISIBLE (-6250 1750);
FORCEADD CAP..1
(-6575 1550);
FORCEPROP 1 LASTPIN (-6575 1450) $PN 2
J 0
(-6565 1430);
DISPLAY 0.617021 (-6565 1430);
PAINT ORANGE (-6565 1430);
FORCEPROP 1 LAST VALUE 10UF
J 0
(-6525 1600);
DISPLAY 0.617021 (-6525 1600);
PAINT SKYBLUE (-6525 1600);
FORCEPROP 1 LAST LOCATION C9P25
J 0
(-6525 1650);
DISPLAY 0.617021 (-6525 1650);
PAINT AQUA (-6525 1650);
FORCEPROP 1 LASTPIN (-6575 1650) $PN 1
J 0
(-6565 1630);
DISPLAY 0.617021 (-6565 1630);
PAINT ORANGE (-6565 1630);
FORCEPROP 1 LAST VOLTAGE 16V
J 0
(-6525 1550);
DISPLAY 0.617021 (-6525 1550);
PAINT SKYBLUE (-6525 1550);
FORCEPROP 1 LAST TOLERANCE 10%
J 0
(-6525 1500);
DISPLAY 0.617021 (-6525 1500);
PAINT SKYBLUE (-6525 1500);
FORCEPROP 1 LAST MATERIAL X6S
J 0
(-6525 1450);
DISPLAY 0.617021 (-6525 1450);
PAINT SKYBLUE (-6525 1450);
FORCEPROP 1 LAST PART_NUMBER C95333-007
J 0
(-6525 1400);
DISPLAY 0.617021 (-6525 1400);
PAINT BLUE (-6525 1400);
FORCEPROP 1 LAST PACK_TYPE 0805
J 0
(-6525 1350);
DISPLAY 0.617021 (-6525 1350);
PAINT SKYBLUE (-6525 1350);
FORCEPROP 2 LAST CDS_LIB mstr_discrete
J 0
(-6575 1550);
PAINT ORANGE (-6575 1550);
DISPLAY INVISIBLE (-6575 1550);
FORCEPROP 2 LAST ROOM PVCCIN_CPU1_PWR_VR
J 0
(-6525 1700);
DISPLAY 1.361702 (-6525 1700);
PAINT ORANGE (-6525 1700);
DISPLAY INVISIBLE (-6525 1700);
FORCEPROP 1 LAST PATH I51
J 0
(-6525 1700);
DISPLAY 0.978723 (-6525 1700);
PAINT WHITE (-6525 1700);
DISPLAY INVISIBLE (-6525 1700);
FORCEPROP 2 LAST SEC 1
J 0
(-6525 1750);
DISPLAY 0.680851 (-6525 1750);
PAINT MONO (-6525 1750);
DISPLAY INVISIBLE (-6525 1750);
FORCEPROP 2 LAST SEC_TYPE 0805
J 0
(-6525 1750);
DISPLAY 1.021277 (-6525 1750);
PAINT ORANGE (-6525 1750);
DISPLAY INVISIBLE (-6525 1750);
FORCEADD OFFPAGE..1
(-6350 1150);
FORCEPROP 2 LAST $XR0 206 
J 0
(-6602 1150);
DISPLAY 0.638298 (-6602 1150);
PAINT MONO (-6602 1150);
FORCEPROP 2 LAST PATH I52
J 0
(-6595 1200);
DISPLAY 1.021277 (-6595 1200);
PAINT ORANGE (-6595 1200);
DISPLAY INVISIBLE (-6595 1200);
FORCEPROP 2 LAST ROOM PVCCIN_CPU1_PWR_VR
J 0
(-6750 1225);
DISPLAY 1.936170 (-6750 1225);
PAINT ORANGE (-6750 1225);
DISPLAY INVISIBLE (-6750 1225);
FORCEPROP 2 LAST BOM_COST PROC_VRD_VCCIN_CPU0
J 0
(-6600 1200);
DISPLAY 1.446809 (-6600 1200);
PAINT MONO (-6600 1200);
DISPLAY INVISIBLE (-6600 1200);
FORCEPROP 2 LAST CDS_LIB mstr_standard
J 0
(-6350 1150);
PAINT ORANGE (-6350 1150);
DISPLAY INVISIBLE (-6350 1150);
FORCEPROP 1 LAST OFFPAGE TRUE
J 0
(-6025 1025);
DISPLAY 1.680851 (-6025 1025);
PAINT GREEN (-6025 1025);
DISPLAY INVISIBLE (-6025 1025);
FORCEPROP 1 LAST COMMENT_BODY TRUE
J 0
(-6225 1050);
DISPLAY 1.680851 (-6225 1050);
PAINT GREEN (-6225 1050);
DISPLAY INVISIBLE (-6225 1050);
FORCEADD VCC_CORE..1
(-6300 1900);
FORCEPROP 3 LASTPIN (-6300 1850) SIG_NAME VR_FET_SW_P12V_STBY_PVCCIN_CPU1\g
J 0
(-6290 1860);
DISPLAY 0.659574 (-6290 1860);
PAINT MONO (-6290 1860);
DISPLAY INVISIBLE (-6290 1860);
FORCEPROP 1 LAST HDL_POWER VR_FET_SW_P12V_STBY_PVCCIN_CPU1
J 1
(-6275 1950);
DISPLAY 0.617021 (-6275 1950);
PAINT GREEN (-6275 1950);
FORCEPROP 2 LAST CDS_LIB mstr_symbols
J 0
(-6300 1900);
PAINT ORANGE (-6300 1900);
DISPLAY INVISIBLE (-6300 1900);
FORCEPROP 1 LAST PATH I53
J 0
(-6250 1925);
DISPLAY 0.872340 (-6250 1925);
PAINT AQUA (-6250 1925);
DISPLAY INVISIBLE (-6250 1925);
FORCEADD CAP..1
(-6875 1550);
FORCEPROP 1 LASTPIN (-6875 1450) $PN 2
J 0
(-6865 1430);
DISPLAY 0.617021 (-6865 1430);
PAINT ORANGE (-6865 1430);
FORCEPROP 1 LASTPIN (-6875 1650) $PN 1
J 0
(-6865 1630);
DISPLAY 0.617021 (-6865 1630);
PAINT ORANGE (-6865 1630);
FORCEPROP 1 LAST LOCATION C9P26
J 0
(-6825 1650);
DISPLAY 0.617021 (-6825 1650);
PAINT AQUA (-6825 1650);
FORCEPROP 1 LAST VALUE 10UF
J 0
(-6825 1600);
DISPLAY 0.617021 (-6825 1600);
PAINT SKYBLUE (-6825 1600);
FORCEPROP 1 LAST VOLTAGE 16V
J 0
(-6825 1550);
DISPLAY 0.617021 (-6825 1550);
PAINT SKYBLUE (-6825 1550);
FORCEPROP 1 LAST TOLERANCE 10%
J 0
(-6825 1500);
DISPLAY 0.617021 (-6825 1500);
PAINT SKYBLUE (-6825 1500);
FORCEPROP 1 LAST MATERIAL X6S
J 0
(-6825 1450);
DISPLAY 0.617021 (-6825 1450);
PAINT SKYBLUE (-6825 1450);
FORCEPROP 1 LAST PACK_TYPE 0805
J 0
(-6825 1350);
DISPLAY 0.617021 (-6825 1350);
PAINT SKYBLUE (-6825 1350);
FORCEPROP 1 LAST PART_NUMBER C95333-007
J 0
(-6825 1400);
DISPLAY 0.617021 (-6825 1400);
PAINT BLUE (-6825 1400);
FORCEPROP 2 LAST CDS_LIB mstr_discrete
J 0
(-6875 1550);
PAINT ORANGE (-6875 1550);
DISPLAY INVISIBLE (-6875 1550);
FORCEPROP 2 LAST SEC_TYPE 0805
J 0
(-6825 1750);
DISPLAY 1.021277 (-6825 1750);
PAINT ORANGE (-6825 1750);
DISPLAY INVISIBLE (-6825 1750);
FORCEPROP 2 LAST SEC 1
J 0
(-6825 1750);
DISPLAY 0.680851 (-6825 1750);
PAINT MONO (-6825 1750);
DISPLAY INVISIBLE (-6825 1750);
FORCEPROP 1 LAST PATH I54
J 0
(-6825 1700);
DISPLAY 0.978723 (-6825 1700);
PAINT WHITE (-6825 1700);
DISPLAY INVISIBLE (-6825 1700);
FORCEPROP 2 LAST ROOM PVCCIN_CPU1_PWR_VR
J 0
(-6825 1700);
DISPLAY 1.361702 (-6825 1700);
PAINT ORANGE (-6825 1700);
DISPLAY INVISIBLE (-6825 1700);
FORCEADD GND..1
(-6875 1150);
FORCEPROP 3 LASTPIN (-6875 1200) SIG_NAME GND\g
J 0
(-6865 1210);
DISPLAY 0.659574 (-6865 1210);
PAINT MONO (-6865 1210);
DISPLAY INVISIBLE (-6865 1210);
FORCEPROP 2 LAST ROOM PVCCIN_CPU1_PWR_VR
J 0
(-7425 1225);
DISPLAY 1.936170 (-7425 1225);
PAINT ORANGE (-7425 1225);
DISPLAY INVISIBLE (-7425 1225);
FORCEPROP 2 LAST BOM_COST PROC_VRD_VCCIN_CPU0
J 0
(-7250 1225);
DISPLAY 1.446809 (-7250 1225);
PAINT MONO (-7250 1225);
DISPLAY INVISIBLE (-7250 1225);
FORCEPROP 1 LAST SIZE 1B
J 0
(-6800 1100);
DISPLAY 1.723404 (-6800 1100);
PAINT GREEN (-6800 1100);
DISPLAY INVISIBLE (-6800 1100);
FORCEPROP 1 LAST VOLTAGE 0
J 0
(-6875 1150);
PAINT SKYBLUE (-6875 1150);
DISPLAY INVISIBLE (-6875 1150);
FORCEPROP 2 LAST CDS_LIB mstr_symbols
J 0
(-6875 1150);
PAINT ORANGE (-6875 1150);
DISPLAY INVISIBLE (-6875 1150);
FORCEPROP 1 LAST PATH I55
J 0
(-6800 1150);
DISPLAY 0.872340 (-6800 1150);
PAINT AQUA (-6800 1150);
DISPLAY INVISIBLE (-6800 1150);
FORCEPROP 1 LAST BODY_TYPE PLUMBING
J 0
(-6920 1107);
DISPLAY 0.340426 (-6920 1107);
PAINT GREEN (-6920 1107);
DISPLAY INVISIBLE (-6920 1107);
FORCEPROP 1 LAST HDL_POWER GND
J 0
(-6875 1300);
DISPLAY 1.723404 (-6875 1300);
PAINT GREEN (-6875 1300);
DISPLAY INVISIBLE (-6875 1300);
FORCEADD P5V_STBY..1
(-4225 4800);
FORCEPROP 3 LASTPIN (-4225 4750) SIG_NAME P5V_STBY\g
J 0
(-4215 4760);
DISPLAY 0.659574 (-4215 4760);
PAINT MONO (-4215 4760);
DISPLAY INVISIBLE (-4215 4760);
FORCEPROP 1 LAST PATH I56
J 0
(-4180 4802);
DISPLAY 0.340426 (-4180 4802);
PAINT GREEN (-4180 4802);
DISPLAY INVISIBLE (-4180 4802);
FORCEPROP 2 LAST CDS_LIB mstr_symbols
J 0
(-4225 4800);
PAINT ORANGE (-4225 4800);
DISPLAY INVISIBLE (-4225 4800);
FORCEPROP 1 LAST SIZE 1B
J 0
(-4180 4822);
DISPLAY 0.340426 (-4180 4822);
PAINT GREEN (-4180 4822);
DISPLAY INVISIBLE (-4180 4822);
FORCEPROP 1 LAST VOLTAGE 5.0V
J 0
(-4270 4757);
DISPLAY 0.340426 (-4270 4757);
PAINT SKYBLUE (-4270 4757);
DISPLAY INVISIBLE (-4270 4757);
FORCEPROP 1 LAST BODY_TYPE PLUMBING
J 0
(-4270 4757);
DISPLAY 0.340426 (-4270 4757);
PAINT GREEN (-4270 4757);
DISPLAY INVISIBLE (-4270 4757);
FORCEPROP 1 LAST HDL_POWER P5V_STBY
J 0
(-4525 4675);
DISPLAY 0.872340 (-4525 4675);
PAINT ORANGE (-4525 4675);
DISPLAY INVISIBLE (-4525 4675);
FORCEADD P5V_STBY..1
(-4750 2200);
FORCEPROP 3 LASTPIN (-4750 2150) SIG_NAME P5V_STBY\g
J 0
(-4740 2160);
DISPLAY 0.659574 (-4740 2160);
PAINT MONO (-4740 2160);
DISPLAY INVISIBLE (-4740 2160);
FORCEPROP 2 LAST CDS_LIB mstr_symbols
J 0
(-4750 2200);
PAINT ORANGE (-4750 2200);
DISPLAY INVISIBLE (-4750 2200);
FORCEPROP 1 LAST VOLTAGE 5.0V
J 0
(-4795 2157);
DISPLAY 0.340426 (-4795 2157);
PAINT SKYBLUE (-4795 2157);
DISPLAY INVISIBLE (-4795 2157);
FORCEPROP 1 LAST PATH I57
J 0
(-4705 2202);
DISPLAY 0.340426 (-4705 2202);
PAINT GREEN (-4705 2202);
DISPLAY INVISIBLE (-4705 2202);
FORCEPROP 1 LAST SIZE 1B
J 0
(-4705 2222);
DISPLAY 0.340426 (-4705 2222);
PAINT GREEN (-4705 2222);
DISPLAY INVISIBLE (-4705 2222);
FORCEPROP 1 LAST BODY_TYPE PLUMBING
J 0
(-4795 2157);
DISPLAY 0.340426 (-4795 2157);
PAINT GREEN (-4795 2157);
DISPLAY INVISIBLE (-4795 2157);
FORCEPROP 1 LAST HDL_POWER P5V_STBY
J 0
(-5050 2075);
DISPLAY 0.872340 (-5050 2075);
PAINT ORANGE (-5050 2075);
DISPLAY INVISIBLE (-5050 2075);
FORCEADD CAP_A..1
(-650 3350);
FORCEPROP 1 LAST VALUE 22.0UF
J 0
(-600 3450);
DISPLAY 0.617021 (-600 3450);
PAINT SKYBLUE (-600 3450);
FORCEPROP 1 LAST VOLTAGE 4V
J 0
(-600 3400);
DISPLAY 0.617021 (-600 3400);
PAINT SKYBLUE (-600 3400);
FORCEPROP 1 LAST TOLERANCE 20%
J 0
(-600 3350);
DISPLAY 0.617021 (-600 3350);
PAINT SKYBLUE (-600 3350);
FORCEPROP 1 LASTPIN (-650 3450) $PN 1
J 0
(-640 3430);
DISPLAY 0.617021 (-640 3430);
PAINT ORANGE (-640 3430);
FORCEPROP 1 LAST LOCATION C1E9
J 0
(-600 3500);
DISPLAY 0.617021 (-600 3500);
PAINT AQUA (-600 3500);
FORCEPROP 1 LAST PART_NUMBER E15431-004
J 0
(-600 3250);
DISPLAY 0.617021 (-600 3250);
PAINT BLUE (-600 3250);
FORCEPROP 1 LAST PACK_TYPE 0603V
J 0
(-600 3200);
DISPLAY 0.617021 (-600 3200);
PAINT SKYBLUE (-600 3200);
FORCEPROP 1 LAST MATERIAL X6S
J 0
(-600 3300);
DISPLAY 0.617021 (-600 3300);
PAINT SKYBLUE (-600 3300);
FORCEPROP 1 LASTPIN (-650 3250) $PN 2
J 0
(-640 3230);
DISPLAY 0.617021 (-640 3230);
PAINT ORANGE (-640 3230);
FORCEPROP 0 LAST GROUP PWR_MLCC_CAP
J 0
(-594 3087);
DISPLAY 0.638298 (-594 3087);
PAINT BROWN (-594 3087);
DISPLAY BOTH (-594 3087);
FORCEPROP 2 LAST CDS_LIB dev_discrete
J 0
(-650 3350);
PAINT ORANGE (-650 3350);
DISPLAY INVISIBLE (-650 3350);
FORCEPROP 2 LAST CDS_LOCATION C1E9
J 0
(-600 3450);
DISPLAY 0.617021 (-600 3450);
PAINT AQUA (-600 3450);
DISPLAY INVISIBLE (-600 3450);
FORCEPROP 1 LAST PATH I58
J 0
(-600 3500);
DISPLAY 0.978723 (-600 3500);
PAINT WHITE (-600 3500);
DISPLAY INVISIBLE (-600 3500);
FORCEPROP 2 LAST SEC 1
J 0
(-600 3550);
DISPLAY 0.680851 (-600 3550);
PAINT MONO (-600 3550);
DISPLAY INVISIBLE (-600 3550);
FORCEPROP 2 LAST CDS_SEC 1
J 0
(-600 3500);
PAINT ORANGE (-600 3500);
DISPLAY INVISIBLE (-600 3500);
FORCEPROP 2 LAST SEC_TYPE 0603V
J 0
(-600 3550);
DISPLAY 1.021277 (-600 3550);
PAINT ORANGE (-600 3550);
DISPLAY INVISIBLE (-600 3550);
FORCEADD CAP_A..1
(-750 750);
FORCEPROP 1 LASTPIN (-750 650) $PN 2
J 0
(-740 630);
DISPLAY 0.617021 (-740 630);
PAINT ORANGE (-740 630);
FORCEPROP 1 LAST PACK_TYPE 0603V
J 0
(-700 600);
DISPLAY 0.617021 (-700 600);
PAINT SKYBLUE (-700 600);
FORCEPROP 1 LAST PART_NUMBER E15431-004
J 0
(-700 650);
DISPLAY 0.617021 (-700 650);
PAINT BLUE (-700 650);
FORCEPROP 1 LAST MATERIAL X6S
J 0
(-700 700);
DISPLAY 0.617021 (-700 700);
PAINT SKYBLUE (-700 700);
FORCEPROP 1 LASTPIN (-750 850) $PN 1
J 0
(-740 830);
DISPLAY 0.617021 (-740 830);
PAINT ORANGE (-740 830);
FORCEPROP 1 LAST LOCATION C9P3
J 0
(-700 900);
DISPLAY 0.617021 (-700 900);
PAINT AQUA (-700 900);
FORCEPROP 1 LAST VOLTAGE 4V
J 0
(-700 800);
DISPLAY 0.617021 (-700 800);
PAINT SKYBLUE (-700 800);
FORCEPROP 1 LAST TOLERANCE 20%
J 0
(-700 750);
DISPLAY 0.617021 (-700 750);
PAINT SKYBLUE (-700 750);
FORCEPROP 1 LAST VALUE 22.0UF
J 0
(-700 850);
DISPLAY 0.617021 (-700 850);
PAINT SKYBLUE (-700 850);
FORCEPROP 0 LAST GROUP PWR_MLCC_CAP
J 0
(-694 487);
DISPLAY 0.638298 (-694 487);
PAINT BROWN (-694 487);
DISPLAY BOTH (-694 487);
FORCEPROP 2 LAST CDS_SEC 1
J 0
(-700 900);
PAINT ORANGE (-700 900);
DISPLAY INVISIBLE (-700 900);
FORCEPROP 2 LAST SEC_TYPE 0603V
J 0
(-700 950);
DISPLAY 1.021277 (-700 950);
PAINT ORANGE (-700 950);
DISPLAY INVISIBLE (-700 950);
FORCEPROP 2 LAST SEC 1
J 0
(-700 950);
DISPLAY 0.680851 (-700 950);
PAINT MONO (-700 950);
DISPLAY INVISIBLE (-700 950);
FORCEPROP 1 LAST PATH I59
J 0
(-700 900);
DISPLAY 0.978723 (-700 900);
PAINT WHITE (-700 900);
DISPLAY INVISIBLE (-700 900);
FORCEPROP 2 LAST CDS_LOCATION C9P3
J 0
(-700 850);
DISPLAY 0.617021 (-700 850);
PAINT AQUA (-700 850);
DISPLAY INVISIBLE (-700 850);
FORCEPROP 2 LAST CDS_LIB dev_discrete
J 0
(-750 750);
PAINT ORANGE (-750 750);
DISPLAY INVISIBLE (-750 750);
FORCEADD OFFPAGE..2
(-1400 4425);
FORCEPROP 2 LAST $XR0 206 
J 0
(-1211 4425);
DISPLAY 0.638298 (-1211 4425);
PAINT MONO (-1211 4425);
FORCEPROP 2 LAST CDS_LIB mstr_standard
J 0
(-1400 4425);
PAINT ORANGE (-1400 4425);
DISPLAY INVISIBLE (-1400 4425);
FORCEPROP 2 LAST BOM_COST PROC_VRD_VCCIN_CPU0
J 0
(-1200 4475);
DISPLAY 1.446809 (-1200 4475);
PAINT MONO (-1200 4475);
DISPLAY INVISIBLE (-1200 4475);
FORCEPROP 2 LAST PATH I62
J 0
(-1225 4500);
DISPLAY 1.021277 (-1225 4500);
PAINT ORANGE (-1225 4500);
DISPLAY INVISIBLE (-1225 4500);
FORCEPROP 2 LAST ROOM PVCCIN_CPU1_PWR_VR
J 0
(-1800 4500);
DISPLAY 1.936170 (-1800 4500);
PAINT ORANGE (-1800 4500);
DISPLAY INVISIBLE (-1800 4500);
FORCEPROP 1 LAST OFFPAGE TRUE
J 0
(-1075 4300);
DISPLAY 1.723404 (-1075 4300);
PAINT GREEN (-1075 4300);
DISPLAY INVISIBLE (-1075 4300);
FORCEPROP 1 LAST COMMENT_BODY TRUE
J 0
(-1445 4330);
DISPLAY 1.723404 (-1445 4330);
PAINT GREEN (-1445 4330);
DISPLAY INVISIBLE (-1445 4330);
FORCEADD OFFPAGE..2
(-950 1800);
FORCEPROP 2 LAST $XR0 206 
J 0
(-761 1800);
DISPLAY 0.638298 (-761 1800);
PAINT MONO (-761 1800);
FORCEPROP 2 LAST BOM_COST PROC_VRD_VCCIN_CPU0
J 0
(-750 1850);
DISPLAY 1.446809 (-750 1850);
PAINT MONO (-750 1850);
DISPLAY INVISIBLE (-750 1850);
FORCEPROP 2 LAST PATH I64
J 0
(-775 1875);
DISPLAY 1.021277 (-775 1875);
PAINT ORANGE (-775 1875);
DISPLAY INVISIBLE (-775 1875);
FORCEPROP 2 LAST CDS_LIB mstr_standard
J 0
(-950 1800);
PAINT ORANGE (-950 1800);
DISPLAY INVISIBLE (-950 1800);
FORCEPROP 2 LAST ROOM PVCCIN_CPU1_PWR_VR
J 0
(-1350 1875);
DISPLAY 1.936170 (-1350 1875);
PAINT ORANGE (-1350 1875);
DISPLAY INVISIBLE (-1350 1875);
FORCEPROP 1 LAST OFFPAGE TRUE
J 0
(-625 1675);
DISPLAY 1.723404 (-625 1675);
PAINT GREEN (-625 1675);
DISPLAY INVISIBLE (-625 1675);
FORCEPROP 1 LAST COMMENT_BODY TRUE
J 0
(-995 1705);
DISPLAY 1.723404 (-995 1705);
PAINT GREEN (-995 1705);
DISPLAY INVISIBLE (-995 1705);
FORCEADD RES..2
(-700 1425);
FORCEPROP 1 LAST TOLERANCE 1%
J 0
(-655 1450);
DISPLAY 0.617021 (-655 1450);
PAINT SKYBLUE (-655 1450);
FORCEPROP 1 LASTPIN (-700 1525) $PN 1
J 0
(-695 1487);
DISPLAY 0.617021 (-695 1487);
PAINT ORANGE (-695 1487);
FORCEPROP 1 LAST PART_NUMBER G21796-187
J 0
(-660 1300);
DISPLAY 0.617021 (-660 1300);
PAINT BLUE (-660 1300);
FORCEPROP 1 LASTPIN (-700 1325) $PN 2
J 0
(-695 1335);
DISPLAY 0.617021 (-695 1335);
PAINT ORANGE (-695 1335);
FORCEPROP 1 LAST LOCATION R1E13
J 0
(-655 1550);
DISPLAY 0.617021 (-655 1550);
PAINT AQUA (-655 1550);
FORCEPROP 1 LAST VALUE 68.1K
J 0
(-655 1500);
DISPLAY 0.617021 (-655 1500);
PAINT SKYBLUE (-655 1500);
FORCEPROP 1 LAST WATTAGE 1/16W
J 0
(-660 1400);
DISPLAY 0.617021 (-660 1400);
PAINT SKYBLUE (-660 1400);
FORCEPROP 1 LAST MATERIAL EMPTY
J 0
(-660 1350);
DISPLAY 0.617021 (-660 1350);
PAINT RED (-660 1350);
FORCEPROP 1 LAST PACK_TYPE 0402
J 0
(-660 1250);
DISPLAY 0.617021 (-660 1250);
PAINT SKYBLUE (-660 1250);
FORCEPROP 2 LAST CDS_SEC 1
J 0
(-650 1650);
PAINT MONO (-650 1650);
DISPLAY INVISIBLE (-650 1650);
FORCEPROP 2 LAST $SEC 1
J 0
(-650 1650);
PAINT MONO (-650 1650);
DISPLAY INVISIBLE (-650 1650);
FORCEPROP 1 LAST PATH I67
J 0
(-650 1600);
DISPLAY 0.978723 (-650 1600);
PAINT WHITE (-650 1600);
DISPLAY INVISIBLE (-650 1600);
FORCEPROP 2 LAST CDS_LIB mstr_discrete
J 0
(-700 1425);
PAINT ORANGE (-700 1425);
DISPLAY INVISIBLE (-700 1425);
FORCEADD RES..2
(-450 4050);
FORCEPROP 1 LAST PART_NUMBER G21796-187
J 0
(-410 3925);
DISPLAY 0.617021 (-410 3925);
PAINT BLUE (-410 3925);
FORCEPROP 1 LAST PACK_TYPE 0402
J 0
(-410 3875);
DISPLAY 0.617021 (-410 3875);
PAINT SKYBLUE (-410 3875);
FORCEPROP 1 LAST MATERIAL EMPTY
J 0
(-410 3975);
DISPLAY 0.617021 (-410 3975);
PAINT RED (-410 3975);
FORCEPROP 1 LAST WATTAGE 1/16W
J 0
(-410 4025);
DISPLAY 0.617021 (-410 4025);
PAINT SKYBLUE (-410 4025);
FORCEPROP 1 LAST TOLERANCE 1%
J 0
(-405 4075);
DISPLAY 0.617021 (-405 4075);
PAINT SKYBLUE (-405 4075);
FORCEPROP 1 LAST VALUE 68.1K
J 0
(-405 4125);
DISPLAY 0.617021 (-405 4125);
PAINT SKYBLUE (-405 4125);
FORCEPROP 1 LAST LOCATION R1E14
J 0
(-405 4175);
DISPLAY 0.617021 (-405 4175);
PAINT AQUA (-405 4175);
FORCEPROP 1 LASTPIN (-450 4150) $PN 1
J 0
(-445 4112);
DISPLAY 0.617021 (-445 4112);
PAINT ORANGE (-445 4112);
FORCEPROP 1 LASTPIN (-450 3950) $PN 2
J 0
(-445 3960);
DISPLAY 0.617021 (-445 3960);
PAINT ORANGE (-445 3960);
FORCEPROP 2 LAST CDS_SEC 1
J 0
(-400 4275);
PAINT MONO (-400 4275);
DISPLAY INVISIBLE (-400 4275);
FORCEPROP 2 LAST $SEC 1
J 0
(-400 4275);
PAINT MONO (-400 4275);
DISPLAY INVISIBLE (-400 4275);
FORCEPROP 1 LAST PATH I68
J 0
(-400 4225);
DISPLAY 0.978723 (-400 4225);
PAINT WHITE (-400 4225);
DISPLAY INVISIBLE (-400 4225);
FORCEPROP 2 LAST CDS_LIB mstr_discrete
J 0
(-450 4050);
PAINT ORANGE (-450 4050);
DISPLAY INVISIBLE (-450 4050);
FORCEADD GND..1
(-450 3850);
FORCEPROP 3 LASTPIN (-450 3900) SIG_NAME GND\g
J 0
(-440 3910);
DISPLAY 0.659574 (-440 3910);
PAINT MONO (-440 3910);
DISPLAY INVISIBLE (-440 3910);
FORCEPROP 1 LAST SIZE 1B
J 0
(-375 3800);
DISPLAY 1.723404 (-375 3800);
PAINT GREEN (-375 3800);
DISPLAY INVISIBLE (-375 3800);
FORCEPROP 1 LAST PATH I69
J 0
(-375 3850);
DISPLAY 0.872340 (-375 3850);
PAINT AQUA (-375 3850);
DISPLAY INVISIBLE (-375 3850);
FORCEPROP 1 LAST VOLTAGE 0
J 0
(-450 3850);
PAINT SKYBLUE (-450 3850);
DISPLAY INVISIBLE (-450 3850);
FORCEPROP 2 LAST CDS_LIB mstr_symbols
J 0
(-450 3850);
PAINT ORANGE (-450 3850);
DISPLAY INVISIBLE (-450 3850);
FORCEPROP 2 LAST BOM_COST PROC_VRD_VCCIN_CPU0
J 0
(-825 3925);
DISPLAY 1.446809 (-825 3925);
PAINT MONO (-825 3925);
DISPLAY INVISIBLE (-825 3925);
FORCEPROP 2 LAST ROOM PVCCIN_CPU1_PWR_VR
J 0
(-1000 3925);
DISPLAY 1.936170 (-1000 3925);
PAINT ORANGE (-1000 3925);
DISPLAY INVISIBLE (-1000 3925);
FORCEPROP 1 LAST BODY_TYPE PLUMBING
J 0
(-495 3807);
DISPLAY 0.340426 (-495 3807);
PAINT GREEN (-495 3807);
DISPLAY INVISIBLE (-495 3807);
FORCEPROP 1 LAST HDL_POWER GND
J 0
(-450 4000);
DISPLAY 1.723404 (-450 4000);
PAINT GREEN (-450 4000);
DISPLAY INVISIBLE (-450 4000);
FORCEADD PVCCIN_CPU1..1
(-650 3650);
FORCEPROP 3 LASTPIN (-650 3600) SIG_NAME PVCCIN_CPU1\g
J 0
(-640 3610);
DISPLAY 0.659574 (-640 3610);
PAINT MONO (-640 3610);
DISPLAY INVISIBLE (-640 3610);
FORCEPROP 2 LAST CDS_LIB mstr_symbols
J 0
(-650 3650);
PAINT ORANGE (-650 3650);
DISPLAY INVISIBLE (-650 3650);
FORCEPROP 1 LAST PATH I7
J 0
(-600 3675);
DISPLAY 0.872340 (-600 3675);
PAINT AQUA (-600 3675);
DISPLAY INVISIBLE (-600 3675);
FORCEPROP 1 LAST VOLTAGE 2.0V
J 0
(-695 3607);
DISPLAY 0.340426 (-695 3607);
PAINT SKYBLUE (-695 3607);
DISPLAY INVISIBLE (-695 3607);
FORCEPROP 1 LAST BODY_TYPE PLUMBING
J 0
(-695 3607);
DISPLAY 0.340426 (-695 3607);
PAINT GREEN (-695 3607);
DISPLAY INVISIBLE (-695 3607);
FORCEPROP 1 LAST HDL_POWER PVCCIN_CPU1
J 1
(-650 3700);
DISPLAY 0.872340 (-650 3700);
PAINT GREEN (-650 3700);
DISPLAY INVISIBLE (-650 3700);
FORCEADD GND..1
(-700 1200);
FORCEPROP 3 LASTPIN (-700 1250) SIG_NAME GND\g
J 0
(-690 1260);
DISPLAY 0.659574 (-690 1260);
PAINT MONO (-690 1260);
DISPLAY INVISIBLE (-690 1260);
FORCEPROP 1 LAST SIZE 1B
J 0
(-625 1150);
DISPLAY 1.723404 (-625 1150);
PAINT GREEN (-625 1150);
DISPLAY INVISIBLE (-625 1150);
FORCEPROP 1 LAST PATH I70
J 0
(-625 1200);
DISPLAY 0.872340 (-625 1200);
PAINT AQUA (-625 1200);
DISPLAY INVISIBLE (-625 1200);
FORCEPROP 1 LAST VOLTAGE 0
J 0
(-700 1200);
PAINT SKYBLUE (-700 1200);
DISPLAY INVISIBLE (-700 1200);
FORCEPROP 2 LAST CDS_LIB mstr_symbols
J 0
(-700 1200);
PAINT ORANGE (-700 1200);
DISPLAY INVISIBLE (-700 1200);
FORCEPROP 2 LAST BOM_COST PROC_VRD_VCCIN_CPU0
J 0
(-1075 1275);
DISPLAY 1.446809 (-1075 1275);
PAINT MONO (-1075 1275);
DISPLAY INVISIBLE (-1075 1275);
FORCEPROP 2 LAST ROOM PVCCIN_CPU1_PWR_VR
J 0
(-1250 1275);
DISPLAY 1.936170 (-1250 1275);
PAINT ORANGE (-1250 1275);
DISPLAY INVISIBLE (-1250 1275);
FORCEPROP 1 LAST BODY_TYPE PLUMBING
J 0
(-745 1157);
DISPLAY 0.340426 (-745 1157);
PAINT GREEN (-745 1157);
DISPLAY INVISIBLE (-745 1157);
FORCEPROP 1 LAST HDL_POWER GND
J 0
(-700 1350);
DISPLAY 1.723404 (-700 1350);
PAINT GREEN (-700 1350);
DISPLAY INVISIBLE (-700 1350);
FORCEADD CAP_A..1
(-3850 3350);
FORCEPROP 0 LAST POP NOPOP
J 0
(-3800 3100);
DISPLAY 1.021277 (-3800 3100);
PAINT RED (-3800 3100);
FORCEPROP 1 LAST PART_NUMBER A36096-030
J 0
(-3800 3200);
DISPLAY 0.617021 (-3800 3200);
PAINT BLUE (-3800 3200);
FORCEPROP 1 LAST MATERIAL X7R
J 0
(-3800 3250);
DISPLAY 0.617021 (-3800 3250);
PAINT SKYBLUE (-3800 3250);
FORCEPROP 1 LAST TOLERANCE 10%
J 0
(-3800 3300);
DISPLAY 0.617021 (-3800 3300);
PAINT SKYBLUE (-3800 3300);
FORCEPROP 1 LAST VALUE 0.1UF
J 0
(-3800 3400);
DISPLAY 0.617021 (-3800 3400);
PAINT SKYBLUE (-3800 3400);
FORCEPROP 1 LAST VOLTAGE 16V
J 0
(-3800 3350);
DISPLAY 0.617021 (-3800 3350);
PAINT SKYBLUE (-3800 3350);
FORCEPROP 1 LAST PACK_TYPE 0402V
J 0
(-3800 3150);
DISPLAY 0.617021 (-3800 3150);
PAINT SKYBLUE (-3800 3150);
FORCEPROP 1 LASTPIN (-3850 3450) $PN 1
J 0
(-3840 3430);
DISPLAY 0.787234 (-3840 3430);
PAINT ORANGE (-3840 3430);
FORCEPROP 1 LAST LOCATION CT24
J 0
(-3975 3275);
DISPLAY 0.617021 (-3975 3275);
PAINT AQUA (-3975 3275);
FORCEPROP 1 LASTPIN (-3850 3250) $PN 2
J 0
(-3840 3230);
DISPLAY 0.787234 (-3840 3230);
PAINT ORANGE (-3840 3230);
FORCEPROP 2 LAST CDS_LIB dev_discrete
J 0
(-3850 3350);
PAINT MONO (-3850 3350);
DISPLAY INVISIBLE (-3850 3350);
FORCEPROP 1 LAST PATH I71
J 0
(-3800 3500);
DISPLAY 0.978723 (-3800 3500);
PAINT WHITE (-3800 3500);
DISPLAY INVISIBLE (-3800 3500);
FORCEPROP 2 LAST ROOM PVCCIN_CPU0_PWR_VR
J 0
(-3800 3500);
DISPLAY 1.361702 (-3800 3500);
PAINT ORANGE (-3800 3500);
DISPLAY INVISIBLE (-3800 3500);
FORCEPROP 0 LAST SEC 1
J 0
(-3800 3450);
DISPLAY 0.680851 (-3800 3450);
PAINT MONO (-3800 3450);
DISPLAY INVISIBLE (-3800 3450);
FORCEPROP 2 LAST SEC_TYPE 0402V
J 0
(-3800 3550);
DISPLAY 1.021277 (-3800 3550);
PAINT ORANGE (-3800 3550);
DISPLAY INVISIBLE (-3800 3550);
FORCEADD GND..1
(-3850 3025);
FORCEPROP 3 LASTPIN (-3850 3075) SIG_NAME GND\g
J 0
(-3840 3085);
DISPLAY 0.659574 (-3840 3085);
PAINT MONO (-3840 3085);
DISPLAY INVISIBLE (-3840 3085);
FORCEPROP 2 LAST CDS_LIB mstr_symbols
J 0
(-3850 3025);
PAINT MONO (-3850 3025);
DISPLAY INVISIBLE (-3850 3025);
FORCEPROP 1 LAST PATH I72
J 0
(-3775 3025);
DISPLAY 0.872340 (-3775 3025);
PAINT AQUA (-3775 3025);
DISPLAY INVISIBLE (-3775 3025);
FORCEPROP 1 LAST VOLTAGE 0
J 0
(-3850 3025);
PAINT SKYBLUE (-3850 3025);
DISPLAY INVISIBLE (-3850 3025);
FORCEPROP 1 LAST SIZE 1B
J 0
(-3775 2975);
DISPLAY 1.723404 (-3775 2975);
PAINT GREEN (-3775 2975);
DISPLAY INVISIBLE (-3775 2975);
FORCEPROP 2 LAST BOM_COST PROC_VRD_VCCIN_CPU0
J 0
(-4225 3100);
DISPLAY 1.446809 (-4225 3100);
PAINT MONO (-4225 3100);
DISPLAY INVISIBLE (-4225 3100);
FORCEPROP 2 LAST ROOM PVCCIN_CPU0_PWR_VR
J 0
(-4400 3100);
DISPLAY 1.936170 (-4400 3100);
PAINT ORANGE (-4400 3100);
DISPLAY INVISIBLE (-4400 3100);
FORCEPROP 1 LAST BODY_TYPE PLUMBING
J 0
(-3895 2982);
DISPLAY 0.340426 (-3895 2982);
PAINT GREEN (-3895 2982);
DISPLAY INVISIBLE (-3895 2982);
FORCEPROP 1 LAST HDL_POWER GND
J 0
(-3850 3175);
DISPLAY 1.723404 (-3850 3175);
PAINT GREEN (-3850 3175);
DISPLAY INVISIBLE (-3850 3175);
FORCEADD CAP..1
(-2125 3850);
FORCEPROP 1 LAST PACK_TYPE 0402LF
J 0
(-2075 3650);
DISPLAY 0.617021 (-2075 3650);
PAINT SKYBLUE (-2075 3650);
FORCEPROP 1 LAST PART_NUMBER A36096-046
J 0
(-2075 3700);
DISPLAY 0.617021 (-2075 3700);
PAINT BLUE (-2075 3700);
FORCEPROP 1 LAST MATERIAL X7R
J 0
(-2075 3750);
DISPLAY 0.617021 (-2075 3750);
PAINT SKYBLUE (-2075 3750);
FORCEPROP 1 LAST TOLERANCE 10%
J 0
(-2075 3800);
DISPLAY 0.617021 (-2075 3800);
PAINT SKYBLUE (-2075 3800);
FORCEPROP 1 LAST VOLTAGE 50V
J 0
(-2075 3850);
DISPLAY 0.617021 (-2075 3850);
PAINT SKYBLUE (-2075 3850);
FORCEPROP 1 LAST VALUE 1000PF
J 0
(-2075 3900);
DISPLAY 0.617021 (-2075 3900);
PAINT SKYBLUE (-2075 3900);
FORCEPROP 0 LAST POP NOPOP
J 0
(-2075 3950);
DISPLAY 1.021277 (-2075 3950);
PAINT RED (-2075 3950);
FORCEPROP 1 LASTPIN (-2125 3950) $PN 1
J 0
(-2115 3930);
DISPLAY 0.787234 (-2115 3930);
PAINT ORANGE (-2115 3930);
FORCEPROP 1 LASTPIN (-2125 3750) $PN 2
J 0
(-2115 3730);
DISPLAY 0.787234 (-2115 3730);
PAINT ORANGE (-2115 3730);
FORCEPROP 1 LAST LOCATION CT22
J 0
(-2275 3850);
DISPLAY 0.617021 (-2275 3850);
PAINT AQUA (-2275 3850);
FORCEPROP 2 LAST CDS_LIB mstr_discrete
J 0
(-2125 3850);
PAINT MONO (-2125 3850);
DISPLAY INVISIBLE (-2125 3850);
FORCEPROP 1 LAST PATH I74
J 0
(-2075 4000);
DISPLAY 0.978723 (-2075 4000);
PAINT WHITE (-2075 4000);
DISPLAY INVISIBLE (-2075 4000);
FORCEPROP 0 LAST ROOM VDDQ_KLM_PWR_VR
J 0
(-2075 4050);
DISPLAY 1.021277 (-2075 4050);
PAINT ORANGE (-2075 4050);
DISPLAY INVISIBLE (-2075 4050);
FORCEPROP 0 LAST SEC 1
J 0
(-2075 4000);
DISPLAY 0.680851 (-2075 4000);
PAINT MONO (-2075 4000);
DISPLAY INVISIBLE (-2075 4000);
FORCEPROP 2 LAST SEC_TYPE 0402LF
J 0
(-2075 4050);
DISPLAY 1.021277 (-2075 4050);
PAINT ORANGE (-2075 4050);
DISPLAY INVISIBLE (-2075 4050);
FORCEADD GND..1
(-2125 3650);
FORCEPROP 3 LASTPIN (-2125 3700) SIG_NAME GND\g
J 0
(-2115 3710);
DISPLAY 0.659574 (-2115 3710);
PAINT MONO (-2115 3710);
DISPLAY INVISIBLE (-2115 3710);
FORCEPROP 2 LAST CDS_LIB mstr_symbols
J 0
(-2125 3650);
PAINT MONO (-2125 3650);
DISPLAY INVISIBLE (-2125 3650);
FORCEPROP 1 LAST PATH I75
J 0
(-2050 3650);
DISPLAY 0.872340 (-2050 3650);
PAINT AQUA (-2050 3650);
DISPLAY INVISIBLE (-2050 3650);
FORCEPROP 1 LAST SIZE 1B
J 0
(-2050 3600);
DISPLAY 1.170213 (-2050 3600);
PAINT AQUA (-2050 3600);
DISPLAY INVISIBLE (-2050 3600);
FORCEPROP 1 LAST VOLTAGE 0
J 0
(-2125 3650);
PAINT SKYBLUE (-2125 3650);
DISPLAY INVISIBLE (-2125 3650);
FORCEPROP 2 LAST ROOM VDDQ_KLM_PWR_VR
J 0
(-2700 3725);
DISPLAY 1.361702 (-2700 3725);
PAINT ORANGE (-2700 3725);
DISPLAY INVISIBLE (-2700 3725);
FORCEPROP 1 LAST BODY_TYPE PLUMBING
J 0
(-2170 3607);
DISPLAY 0.340426 (-2170 3607);
PAINT GREEN (-2170 3607);
DISPLAY INVISIBLE (-2170 3607);
FORCEPROP 1 LAST HDL_POWER GND
J 0
(-2125 3800);
DISPLAY 1.170213 (-2125 3800);
PAINT GREEN (-2125 3800);
DISPLAY INVISIBLE (-2125 3800);
FORCEADD GND..1
(-2225 2850);
FORCEPROP 3 LASTPIN (-2225 2900) SIG_NAME GND\g
J 0
(-2215 2910);
DISPLAY 0.659574 (-2215 2910);
PAINT MONO (-2215 2910);
DISPLAY INVISIBLE (-2215 2910);
FORCEPROP 2 LAST ROOM PVCCIN_CPU0_PWR_VR
J 0
(-2775 2925);
DISPLAY 1.936170 (-2775 2925);
PAINT ORANGE (-2775 2925);
DISPLAY INVISIBLE (-2775 2925);
FORCEPROP 2 LAST BOM_COST PROC_VRD_VCCIN_CPU0
J 0
(-2600 2925);
DISPLAY 1.446809 (-2600 2925);
PAINT MONO (-2600 2925);
DISPLAY INVISIBLE (-2600 2925);
FORCEPROP 1 LAST VOLTAGE 0
J 0
(-2225 2850);
PAINT SKYBLUE (-2225 2850);
DISPLAY INVISIBLE (-2225 2850);
FORCEPROP 1 LAST SIZE 1B
J 0
(-2150 2800);
DISPLAY 1.723404 (-2150 2800);
PAINT GREEN (-2150 2800);
DISPLAY INVISIBLE (-2150 2800);
FORCEPROP 1 LAST PATH I78
J 0
(-2150 2850);
DISPLAY 0.872340 (-2150 2850);
PAINT AQUA (-2150 2850);
DISPLAY INVISIBLE (-2150 2850);
FORCEPROP 2 LAST CDS_LIB mstr_symbols
J 0
(-2225 2850);
PAINT MONO (-2225 2850);
DISPLAY INVISIBLE (-2225 2850);
FORCEPROP 1 LAST BODY_TYPE PLUMBING
J 0
(-2270 2807);
DISPLAY 0.340426 (-2270 2807);
PAINT GREEN (-2270 2807);
DISPLAY INVISIBLE (-2270 2807);
FORCEPROP 1 LAST HDL_POWER GND
J 0
(-2225 3000);
DISPLAY 1.723404 (-2225 3000);
PAINT GREEN (-2225 3000);
DISPLAY INVISIBLE (-2225 3000);
FORCEADD CAP_A..1
(-1100 3350);
FORCEPROP 1 LAST PART_NUMBER E15431-004
J 0
(-1050 3250);
DISPLAY 0.617021 (-1050 3250);
PAINT BLUE (-1050 3250);
FORCEPROP 1 LAST PACK_TYPE 0603V
J 0
(-1050 3200);
DISPLAY 0.617021 (-1050 3200);
PAINT SKYBLUE (-1050 3200);
FORCEPROP 1 LAST MATERIAL X6S
J 0
(-1050 3300);
DISPLAY 0.617021 (-1050 3300);
PAINT SKYBLUE (-1050 3300);
FORCEPROP 1 LAST TOLERANCE 20%
J 0
(-1050 3350);
DISPLAY 0.617021 (-1050 3350);
PAINT SKYBLUE (-1050 3350);
FORCEPROP 1 LAST VOLTAGE 4V
J 0
(-1050 3400);
DISPLAY 0.617021 (-1050 3400);
PAINT SKYBLUE (-1050 3400);
FORCEPROP 1 LAST VALUE 22.0UF
J 0
(-1050 3450);
DISPLAY 0.617021 (-1050 3450);
PAINT SKYBLUE (-1050 3450);
FORCEPROP 1 LAST LOCATION C9R8
J 0
(-1050 3500);
DISPLAY 0.617021 (-1050 3500);
PAINT AQUA (-1050 3500);
FORCEPROP 1 LASTPIN (-1100 3450) $PN 1
J 0
(-1090 3430);
DISPLAY 0.617021 (-1090 3430);
PAINT GREEN (-1090 3430);
FORCEPROP 1 LASTPIN (-1100 3250) $PN 2
J 0
(-1090 3230);
DISPLAY 0.617021 (-1090 3230);
PAINT GREEN (-1090 3230);
FORCEPROP 0 LAST GROUP PWR_MLCC_CAP
J 0
(-1044 3137);
DISPLAY 0.638298 (-1044 3137);
PAINT BROWN (-1044 3137);
DISPLAY BOTH (-1044 3137);
FORCEPROP 2 LAST ROOM PVCCIN_CPU1_PWR_VR
J 0
(-1050 3500);
DISPLAY 1.446809 (-1050 3500);
PAINT MONO (-1050 3500);
DISPLAY INVISIBLE (-1050 3500);
FORCEPROP 1 LAST PATH I8
J 0
(-1050 3500);
DISPLAY 0.978723 (-1050 3500);
PAINT WHITE (-1050 3500);
DISPLAY INVISIBLE (-1050 3500);
FORCEPROP 2 LAST SEC 1
J 0
(-1045 3550);
DISPLAY 0.680851 (-1045 3550);
PAINT MONO (-1045 3550);
DISPLAY INVISIBLE (-1045 3550);
FORCEPROP 2 LAST SEC_TYPE 0603V
J 0
(-1045 3550);
DISPLAY 1.021277 (-1045 3550);
PAINT ORANGE (-1045 3550);
DISPLAY INVISIBLE (-1045 3550);
FORCEPROP 2 LAST CDS_SEC 1
J 0
(-1050 3500);
PAINT ORANGE (-1050 3500);
DISPLAY INVISIBLE (-1050 3500);
FORCEPROP 2 LAST BOM_COST PROC_VRD_VCCIN_CPU0
J 0
(-1050 3500);
DISPLAY 1.446809 (-1050 3500);
PAINT MONO (-1050 3500);
DISPLAY INVISIBLE (-1050 3500);
FORCEPROP 2 LAST CDS_LOCATION C9R8
J 0
(-1050 3450);
DISPLAY 0.617021 (-1050 3450);
PAINT AQUA (-1050 3450);
DISPLAY INVISIBLE (-1050 3450);
FORCEPROP 2 LAST CDS_LIB dev_discrete
J 0
(-1100 3350);
PAINT ORANGE (-1100 3350);
DISPLAY INVISIBLE (-1100 3350);
FORCEADD GND..1
(-3825 500);
FORCEPROP 3 LASTPIN (-3825 550) SIG_NAME GND\g
J 0
(-3815 560);
DISPLAY 0.659574 (-3815 560);
PAINT MONO (-3815 560);
DISPLAY INVISIBLE (-3815 560);
FORCEPROP 2 LAST CDS_LIB mstr_symbols
J 0
(-3825 500);
PAINT MONO (-3825 500);
DISPLAY INVISIBLE (-3825 500);
FORCEPROP 1 LAST PATH I80
J 0
(-3750 500);
DISPLAY 0.872340 (-3750 500);
PAINT AQUA (-3750 500);
DISPLAY INVISIBLE (-3750 500);
FORCEPROP 1 LAST VOLTAGE 0
J 0
(-3825 500);
PAINT SKYBLUE (-3825 500);
DISPLAY INVISIBLE (-3825 500);
FORCEPROP 1 LAST SIZE 1B
J 0
(-3750 450);
DISPLAY 1.723404 (-3750 450);
PAINT GREEN (-3750 450);
DISPLAY INVISIBLE (-3750 450);
FORCEPROP 2 LAST BOM_COST PROC_VRD_VCCIN_CPU0
J 0
(-4200 575);
DISPLAY 1.446809 (-4200 575);
PAINT MONO (-4200 575);
DISPLAY INVISIBLE (-4200 575);
FORCEPROP 2 LAST ROOM PVCCIN_CPU0_PWR_VR
J 0
(-4375 575);
DISPLAY 1.936170 (-4375 575);
PAINT ORANGE (-4375 575);
DISPLAY INVISIBLE (-4375 575);
FORCEPROP 1 LAST BODY_TYPE PLUMBING
J 0
(-3870 457);
DISPLAY 0.340426 (-3870 457);
PAINT GREEN (-3870 457);
DISPLAY INVISIBLE (-3870 457);
FORCEPROP 1 LAST HDL_POWER GND
J 0
(-3825 650);
DISPLAY 1.723404 (-3825 650);
PAINT GREEN (-3825 650);
DISPLAY INVISIBLE (-3825 650);
FORCEADD CAP_A..1
(-3825 750);
FORCEPROP 1 LASTPIN (-3825 850) $PN 1
J 0
(-3815 830);
DISPLAY 0.787234 (-3815 830);
PAINT ORANGE (-3815 830);
FORCEPROP 1 LAST VOLTAGE 16V
J 0
(-3775 750);
DISPLAY 0.617021 (-3775 750);
PAINT SKYBLUE (-3775 750);
FORCEPROP 1 LAST TOLERANCE 10%
J 0
(-3775 700);
DISPLAY 0.617021 (-3775 700);
PAINT SKYBLUE (-3775 700);
FORCEPROP 1 LAST PACK_TYPE 0402V
J 0
(-3775 550);
DISPLAY 0.617021 (-3775 550);
PAINT SKYBLUE (-3775 550);
FORCEPROP 0 LAST POP NOPOP
J 0
(-3775 500);
DISPLAY 1.021277 (-3775 500);
PAINT RED (-3775 500);
FORCEPROP 1 LAST MATERIAL X7R
J 0
(-3775 650);
DISPLAY 0.617021 (-3775 650);
PAINT SKYBLUE (-3775 650);
FORCEPROP 1 LAST LOCATION CT25
J 0
(-3975 725);
DISPLAY 0.617021 (-3975 725);
PAINT AQUA (-3975 725);
FORCEPROP 1 LAST VALUE 0.1UF
J 0
(-3775 800);
DISPLAY 0.617021 (-3775 800);
PAINT SKYBLUE (-3775 800);
FORCEPROP 1 LASTPIN (-3825 650) $PN 2
J 0
(-3815 630);
DISPLAY 0.787234 (-3815 630);
PAINT ORANGE (-3815 630);
FORCEPROP 1 LAST PART_NUMBER A36096-030
J 0
(-3775 600);
DISPLAY 0.617021 (-3775 600);
PAINT BLUE (-3775 600);
FORCEPROP 2 LAST CDS_LIB dev_discrete
J 0
(-3825 750);
PAINT MONO (-3825 750);
DISPLAY INVISIBLE (-3825 750);
FORCEPROP 1 LAST PATH I81
J 0
(-3775 900);
DISPLAY 0.978723 (-3775 900);
PAINT WHITE (-3775 900);
DISPLAY INVISIBLE (-3775 900);
FORCEPROP 2 LAST ROOM PVCCIN_CPU0_PWR_VR
J 0
(-3775 900);
DISPLAY 1.361702 (-3775 900);
PAINT ORANGE (-3775 900);
DISPLAY INVISIBLE (-3775 900);
FORCEPROP 0 LAST SEC 1
J 0
(-3775 850);
DISPLAY 0.680851 (-3775 850);
PAINT MONO (-3775 850);
DISPLAY INVISIBLE (-3775 850);
FORCEPROP 2 LAST SEC_TYPE 0402V
J 0
(-3775 950);
DISPLAY 1.021277 (-3775 950);
PAINT ORANGE (-3775 950);
DISPLAY INVISIBLE (-3775 950);
FORCEADD CAP..1
(-2075 1250);
FORCEPROP 1 LASTPIN (-2075 1150) $PN 2
J 0
(-2065 1130);
DISPLAY 0.787234 (-2065 1130);
PAINT ORANGE (-2065 1130);
FORCEPROP 1 LASTPIN (-2075 1350) $PN 1
J 0
(-2065 1330);
DISPLAY 0.787234 (-2065 1330);
PAINT ORANGE (-2065 1330);
FORCEPROP 1 LAST VALUE 1000PF
J 0
(-2025 1300);
DISPLAY 0.617021 (-2025 1300);
PAINT SKYBLUE (-2025 1300);
FORCEPROP 1 LAST LOCATION CT26
J 0
(-2225 1250);
DISPLAY 0.617021 (-2225 1250);
PAINT AQUA (-2225 1250);
FORCEPROP 1 LAST VOLTAGE 50V
J 0
(-2025 1250);
DISPLAY 0.617021 (-2025 1250);
PAINT SKYBLUE (-2025 1250);
FORCEPROP 1 LAST TOLERANCE 10%
J 0
(-2025 1200);
DISPLAY 0.617021 (-2025 1200);
PAINT SKYBLUE (-2025 1200);
FORCEPROP 1 LAST MATERIAL X7R
J 0
(-2025 1150);
DISPLAY 0.617021 (-2025 1150);
PAINT SKYBLUE (-2025 1150);
FORCEPROP 1 LAST PART_NUMBER A36096-046
J 0
(-2025 1100);
DISPLAY 0.617021 (-2025 1100);
PAINT BLUE (-2025 1100);
FORCEPROP 1 LAST PACK_TYPE 0402LF
J 0
(-2025 1050);
DISPLAY 0.617021 (-2025 1050);
PAINT SKYBLUE (-2025 1050);
FORCEPROP 0 LAST POP NOPOP
J 0
(-2000 1375);
DISPLAY 1.021277 (-2000 1375);
PAINT RED (-2000 1375);
FORCEPROP 2 LAST CDS_LIB mstr_discrete
J 0
(-2075 1250);
PAINT MONO (-2075 1250);
DISPLAY INVISIBLE (-2075 1250);
FORCEPROP 1 LAST PATH I82
J 0
(-2025 1400);
DISPLAY 0.978723 (-2025 1400);
PAINT WHITE (-2025 1400);
DISPLAY INVISIBLE (-2025 1400);
FORCEPROP 0 LAST ROOM VDDQ_KLM_PWR_VR
J 0
(-2025 1450);
DISPLAY 1.021277 (-2025 1450);
PAINT ORANGE (-2025 1450);
DISPLAY INVISIBLE (-2025 1450);
FORCEPROP 0 LAST SEC 1
J 0
(-2050 1400);
DISPLAY 0.680851 (-2050 1400);
PAINT MONO (-2050 1400);
DISPLAY INVISIBLE (-2050 1400);
FORCEPROP 2 LAST SEC_TYPE 0402LF
J 0
(-2025 1450);
DISPLAY 1.021277 (-2025 1450);
PAINT ORANGE (-2025 1450);
DISPLAY INVISIBLE (-2025 1450);
FORCEADD GND..1
(-2075 1050);
FORCEPROP 3 LASTPIN (-2075 1100) SIG_NAME GND\g
J 0
(-2065 1110);
DISPLAY 0.659574 (-2065 1110);
PAINT MONO (-2065 1110);
DISPLAY INVISIBLE (-2065 1110);
FORCEPROP 2 LAST CDS_LIB mstr_symbols
J 0
(-2075 1050);
PAINT MONO (-2075 1050);
DISPLAY INVISIBLE (-2075 1050);
FORCEPROP 1 LAST PATH I83
J 0
(-2000 1050);
DISPLAY 0.872340 (-2000 1050);
PAINT AQUA (-2000 1050);
DISPLAY INVISIBLE (-2000 1050);
FORCEPROP 2 LAST ROOM VDDQ_KLM_PWR_VR
J 0
(-2650 1125);
DISPLAY 1.361702 (-2650 1125);
PAINT ORANGE (-2650 1125);
DISPLAY INVISIBLE (-2650 1125);
FORCEPROP 1 LAST VOLTAGE 0
J 0
(-2075 1050);
PAINT SKYBLUE (-2075 1050);
DISPLAY INVISIBLE (-2075 1050);
FORCEPROP 1 LAST SIZE 1B
J 0
(-2000 1000);
DISPLAY 1.170213 (-2000 1000);
PAINT AQUA (-2000 1000);
DISPLAY INVISIBLE (-2000 1000);
FORCEPROP 1 LAST BODY_TYPE PLUMBING
J 0
(-2120 1007);
DISPLAY 0.340426 (-2120 1007);
PAINT GREEN (-2120 1007);
DISPLAY INVISIBLE (-2120 1007);
FORCEPROP 1 LAST HDL_POWER GND
J 0
(-2075 1200);
DISPLAY 1.170213 (-2075 1200);
PAINT GREEN (-2075 1200);
DISPLAY INVISIBLE (-2075 1200);
FORCEADD GND..1
(-1925 350);
FORCEPROP 3 LASTPIN (-1925 400) SIG_NAME GND\g
J 0
(-1915 410);
DISPLAY 0.659574 (-1915 410);
PAINT MONO (-1915 410);
DISPLAY INVISIBLE (-1915 410);
FORCEPROP 2 LAST CDS_LIB mstr_symbols
J 0
(-1925 350);
PAINT MONO (-1925 350);
DISPLAY INVISIBLE (-1925 350);
FORCEPROP 1 LAST PATH I86
J 0
(-1850 350);
DISPLAY 0.872340 (-1850 350);
PAINT AQUA (-1850 350);
DISPLAY INVISIBLE (-1850 350);
FORCEPROP 1 LAST SIZE 1B
J 0
(-1850 300);
DISPLAY 1.723404 (-1850 300);
PAINT GREEN (-1850 300);
DISPLAY INVISIBLE (-1850 300);
FORCEPROP 1 LAST VOLTAGE 0
J 0
(-1925 350);
PAINT SKYBLUE (-1925 350);
DISPLAY INVISIBLE (-1925 350);
FORCEPROP 2 LAST BOM_COST PROC_VRD_VCCIN_CPU0
J 0
(-2300 425);
DISPLAY 1.446809 (-2300 425);
PAINT MONO (-2300 425);
DISPLAY INVISIBLE (-2300 425);
FORCEPROP 2 LAST ROOM PVCCIN_CPU0_PWR_VR
J 0
(-2475 425);
DISPLAY 1.936170 (-2475 425);
PAINT ORANGE (-2475 425);
DISPLAY INVISIBLE (-2475 425);
FORCEPROP 1 LAST BODY_TYPE PLUMBING
J 0
(-1970 307);
DISPLAY 0.340426 (-1970 307);
PAINT GREEN (-1970 307);
DISPLAY INVISIBLE (-1970 307);
FORCEPROP 1 LAST HDL_POWER GND
J 0
(-1925 500);
DISPLAY 1.723404 (-1925 500);
PAINT GREEN (-1925 500);
DISPLAY INVISIBLE (-1925 500);
FORCEADD GND..1
(-650 3000);
FORCEPROP 3 LASTPIN (-650 3050) SIG_NAME GND\g
J 0
(-640 3060);
DISPLAY 0.659574 (-640 3060);
PAINT MONO (-640 3060);
DISPLAY INVISIBLE (-640 3060);
FORCEPROP 1 LAST PATH I9
J 0
(-575 3000);
DISPLAY 0.872340 (-575 3000);
PAINT AQUA (-575 3000);
DISPLAY INVISIBLE (-575 3000);
FORCEPROP 1 LAST VOLTAGE 0
J 0
(-650 3000);
PAINT SKYBLUE (-650 3000);
DISPLAY INVISIBLE (-650 3000);
FORCEPROP 2 LAST CDS_LIB mstr_symbols
J 0
(-650 3000);
DISPLAY 1.936170 (-650 3000);
PAINT ORANGE (-650 3000);
DISPLAY INVISIBLE (-650 3000);
FORCEPROP 2 LAST BOM_COST PROC_VRD_VCCIN_CPU0
J 0
(-1025 3075);
DISPLAY 1.446809 (-1025 3075);
PAINT MONO (-1025 3075);
DISPLAY INVISIBLE (-1025 3075);
FORCEPROP 2 LAST ROOM PVCCIN_CPU1_PWR_VR
J 0
(-1200 3075);
DISPLAY 1.936170 (-1200 3075);
PAINT ORANGE (-1200 3075);
DISPLAY INVISIBLE (-1200 3075);
FORCEPROP 1 LAST SIZE 1B
J 0
(-575 2950);
DISPLAY 1.723404 (-575 2950);
PAINT GREEN (-575 2950);
DISPLAY INVISIBLE (-575 2950);
FORCEPROP 1 LAST BODY_TYPE PLUMBING
J 0
(-695 2957);
DISPLAY 0.340426 (-695 2957);
PAINT GREEN (-695 2957);
DISPLAY INVISIBLE (-695 2957);
FORCEPROP 1 LAST HDL_POWER GND
J 0
(-650 3150);
DISPLAY 1.723404 (-650 3150);
PAINT GREEN (-650 3150);
DISPLAY INVISIBLE (-650 3150);
FORCEADD CAP..1
(-2225 3400);
FORCEPROP 1 LAST PART_NUMBER A36096-046
J 0
(-1975 3450);
DISPLAY 0.617021 (-1975 3450);
PAINT BLUE (-1975 3450);
FORCEPROP 0 LAST POP NOPOP
J 0
(-2025 3350);
DISPLAY 0.808511 (-2025 3350);
PAINT RED (-2025 3350);
FORCEPROP 1 LASTPIN (-2225 3300) $PN 2
J 0
(-2215 3280);
DISPLAY 0.787234 (-2215 3280);
PAINT ORANGE (-2215 3280);
FORCEPROP 1 LAST MATERIAL X7R
J 0
(-2175 3300);
DISPLAY 0.617021 (-2175 3300);
PAINT SKYBLUE (-2175 3300);
FORCEPROP 1 LAST TOLERANCE 10%
J 0
(-2175 3350);
DISPLAY 0.617021 (-2175 3350);
PAINT SKYBLUE (-2175 3350);
FORCEPROP 1 LAST VOLTAGE 50V
J 0
(-2175 3400);
DISPLAY 0.617021 (-2175 3400);
PAINT SKYBLUE (-2175 3400);
FORCEPROP 1 LAST PACK_TYPE 0402LF
J 0
(-1975 3400);
DISPLAY 0.617021 (-1975 3400);
PAINT SKYBLUE (-1975 3400);
FORCEPROP 1 LAST VALUE 1000PF
J 0
(-2175 3450);
DISPLAY 0.617021 (-2175 3450);
PAINT SKYBLUE (-2175 3450);
FORCEPROP 1 LAST LOCATION CT23
J 0
(-2175 3500);
DISPLAY 0.617021 (-2175 3500);
PAINT AQUA (-2175 3500);
FORCEPROP 1 LASTPIN (-2225 3500) $PN 1
J 0
(-2215 3480);
DISPLAY 0.787234 (-2215 3480);
PAINT ORANGE (-2215 3480);
FORCEPROP 2 LAST CDS_LIB mstr_discrete
J 0
(-2225 3400);
PAINT MONO (-2225 3400);
DISPLAY INVISIBLE (-2225 3400);
FORCEPROP 1 LAST PATH I95
J 0
(-2175 3550);
DISPLAY 0.978723 (-2175 3550);
PAINT WHITE (-2175 3550);
DISPLAY INVISIBLE (-2175 3550);
FORCEPROP 0 LAST ROOM VDDQ_KLM_PWR_VR
J 0
(-2175 3600);
DISPLAY 1.021277 (-2175 3600);
PAINT ORANGE (-2175 3600);
DISPLAY INVISIBLE (-2175 3600);
FORCEPROP 0 LAST SEC 1
J 0
(-2175 3550);
DISPLAY 0.680851 (-2175 3550);
PAINT MONO (-2175 3550);
DISPLAY INVISIBLE (-2175 3550);
FORCEPROP 2 LAST SEC_TYPE 0402LF
J 0
(-2175 3600);
DISPLAY 1.021277 (-2175 3600);
PAINT ORANGE (-2175 3600);
DISPLAY INVISIBLE (-2175 3600);
FORCEADD CAP..1
(-1925 825);
FORCEPROP 1 LAST PART_NUMBER A36096-046
J 0
(-1875 675);
DISPLAY 0.617021 (-1875 675);
PAINT BLUE (-1875 675);
FORCEPROP 0 LAST POP NOPOP
J 0
(-2125 850);
DISPLAY 0.808511 (-2125 850);
PAINT RED (-2125 850);
FORCEPROP 1 LASTPIN (-1925 725) $PN 2
J 0
(-1915 705);
DISPLAY 0.787234 (-1915 705);
PAINT ORANGE (-1915 705);
FORCEPROP 1 LASTPIN (-1925 925) $PN 1
J 0
(-1915 905);
DISPLAY 0.787234 (-1915 905);
PAINT ORANGE (-1915 905);
FORCEPROP 1 LAST LOCATION CT27
J 0
(-1875 925);
DISPLAY 0.617021 (-1875 925);
PAINT AQUA (-1875 925);
FORCEPROP 1 LAST VALUE 1000PF
J 0
(-1875 875);
DISPLAY 0.617021 (-1875 875);
PAINT SKYBLUE (-1875 875);
FORCEPROP 1 LAST MATERIAL X7R
J 0
(-1875 725);
DISPLAY 0.617021 (-1875 725);
PAINT SKYBLUE (-1875 725);
FORCEPROP 1 LAST PACK_TYPE 0402LF
J 0
(-1750 725);
DISPLAY 0.617021 (-1750 725);
PAINT SKYBLUE (-1750 725);
FORCEPROP 1 LAST VOLTAGE 50V
J 0
(-1875 825);
DISPLAY 0.617021 (-1875 825);
PAINT SKYBLUE (-1875 825);
FORCEPROP 1 LAST TOLERANCE 10%
J 0
(-1875 775);
DISPLAY 0.617021 (-1875 775);
PAINT SKYBLUE (-1875 775);
FORCEPROP 0 LAST ROOM VDDQ_KLM_PWR_VR
J 0
(-1875 1025);
DISPLAY 1.021277 (-1875 1025);
PAINT ORANGE (-1875 1025);
DISPLAY INVISIBLE (-1875 1025);
FORCEPROP 1 LAST PATH I96
J 0
(-1875 975);
DISPLAY 0.978723 (-1875 975);
PAINT WHITE (-1875 975);
DISPLAY INVISIBLE (-1875 975);
FORCEPROP 2 LAST CDS_LIB mstr_discrete
J 0
(-1925 825);
PAINT MONO (-1925 825);
DISPLAY INVISIBLE (-1925 825);
FORCEPROP 0 LAST SEC 1
J 0
(-1875 975);
DISPLAY 0.680851 (-1875 975);
PAINT MONO (-1875 975);
DISPLAY INVISIBLE (-1875 975);
FORCEPROP 2 LAST SEC_TYPE 0402LF
J 0
(-1875 1025);
DISPLAY 1.021277 (-1875 1025);
PAINT ORANGE (-1875 1025);
DISPLAY INVISIBLE (-1875 1025);
FORCEADD RES..1
(-4825 3675);
FORCEPROP 1 LAST TOLERANCE 5.0%
J 0
(-4600 3625);
DISPLAY 0.617021 (-4600 3625);
PAINT SKYBLUE (-4600 3625);
FORCEPROP 1 LAST PACK_TYPE 0603
J 0
(-4750 3625);
DISPLAY 0.617021 (-4750 3625);
PAINT SKYBLUE (-4750 3625);
FORCEPROP 1 LAST WATTAGE 1/10W
J 2
(-4475 3525);
DISPLAY 0.617021 (-4475 3525);
PAINT SKYBLUE (-4475 3525);
FORCEPROP 1 LAST MATERIAL CHIP
J 0
(-4600 3575);
DISPLAY 0.617021 (-4600 3575);
PAINT SKYBLUE (-4600 3575);
FORCEPROP 1 LASTPIN (-4725 3675) $PN 2
J 0
(-4763 3687);
DISPLAY 0.787234 (-4763 3687);
PAINT ORANGE (-4763 3687);
FORCEPROP 1 LAST PART_NUMBER G22178-002
J 0
(-4925 3525);
DISPLAY 0.617021 (-4925 3525);
PAINT BLUE (-4925 3525);
FORCEPROP 1 LAST LOCATION RT15
J 0
(-4900 3575);
DISPLAY 0.617021 (-4900 3575);
PAINT AQUA (-4900 3575);
FORCEPROP 1 LAST VALUE 0
J 2
(-4875 3625);
DISPLAY 0.617021 (-4875 3625);
PAINT SKYBLUE (-4875 3625);
FORCEPROP 1 LASTPIN (-4925 3675) $PN 1
J 0
(-4913 3687);
DISPLAY 0.787234 (-4913 3687);
PAINT ORANGE (-4913 3687);
FORCEPROP 2 LAST CDS_LIB mstr_discrete
J 0
(-4825 3675);
PAINT MONO (-4825 3675);
DISPLAY INVISIBLE (-4825 3675);
FORCEPROP 1 LAST PATH I99
J 0
(-4875 3825);
DISPLAY 0.978723 (-4875 3825);
PAINT WHITE (-4875 3825);
DISPLAY INVISIBLE (-4875 3825);
FORCEPROP 0 LAST BOM_COST NT_GBE_BASE
J 0
(-4725 3900);
DISPLAY 1.021277 (-4725 3900);
PAINT ORANGE (-4725 3900);
DISPLAY INVISIBLE (-4725 3900);
FORCEPROP 0 LAST ROOM NIC_SPRV
J 0
(-4725 3800);
DISPLAY 1.021277 (-4725 3800);
PAINT ORANGE (-4725 3800);
DISPLAY INVISIBLE (-4725 3800);
FORCEPROP 0 LAST SEC 1
J 0
(-5075 3775);
DISPLAY 0.680851 (-5075 3775);
PAINT MONO (-5075 3775);
DISPLAY INVISIBLE (-5075 3775);
FORCEPROP 2 LAST SEC_TYPE 0603
J 0
(-4875 3875);
DISPLAY 1.021277 (-4875 3875);
PAINT ORANGE (-4875 3875);
DISPLAY INVISIBLE (-4875 3875);
FORCEADD DNS..2
(-445 4045);
PAINT RED (-445 4045);
FORCEPROP 2 LAST CDS_LIB mstr_misc
J 0
(-445 4045);
PAINT ORANGE (-445 4045);
DISPLAY INVISIBLE (-445 4045);
FORCEPROP 1 LAST COMMENT_BODY TRUE
R 1
J 0
(-370 3820);
DISPLAY 0.872340 (-370 3820);
PAINT GREEN (-370 3820);
DISPLAY INVISIBLE (-370 3820);
FORCEADD DNS..2
(-695 1420);
PAINT RED (-695 1420);
FORCEPROP 2 LAST CDS_LIB mstr_misc
J 0
(-695 1420);
PAINT ORANGE (-695 1420);
DISPLAY INVISIBLE (-695 1420);
FORCEPROP 1 LAST COMMENT_BODY TRUE
R 1
J 0
(-620 1195);
DISPLAY 0.872340 (-620 1195);
PAINT GREEN (-620 1195);
DISPLAY INVISIBLE (-620 1195);
FORCEADD INTEL_CORP_BPAGE..1
(0 0);
FORCEPROP 1 LAST CDS_CON_LAST_MODIFIED Fri Jun 16 17:49:15 2017
J 0
(-1425 325);
PAINT ORANGE (-1425 325);
DISPLAY INVISIBLE (-1425 325);
FORCEPROP 1 LAST CUSTOM_TXT_CDS <CURRENT_DESIGN_SHEET> OF <TOTAL_DESIGN_SHEETS>
J 0
(-500 25);
PAINT ORANGE (-500 25);
FORCEPROP 2 LAST CUSTOM_TXT_CDS <XR_PAGE_TITLE>
J 0
(-7890 5250);
DISPLAY 0.638298 (-7890 5250);
PAINT PINK (-7890 5250);
DISPLAY INVISIBLE (-7890 5250);
FORCEPROP 2 LAST CUSTOM_TXT_CDS <CON_LAST_MODIFIED>
J 0
(-4000 100);
PAINT ORANGE (-4000 100);
FORCEPROP 1 LAST SCH_TITLE VCCIN CPU1 (2 OF 4)
J 0
(-7950 50);
DISPLAY 1.212766 (-7950 50);
PAINT ORANGE (-7950 50);
FORCEPROP 2 LAST PAGE_BORDER TRUE
J 0
(-7890 5250);
DISPLAY 0.638298 (-7890 5250);
PAINT PINK (-7890 5250);
DISPLAY INVISIBLE (-7890 5250);
FORCEPROP 2 LAST CDS_LIB mstr_symbols
J 0
(0 0);
PAINT MONO (0 0);
DISPLAY INVISIBLE (0 0);
FORCEPROP 1 LAST COMMENT_BODY TRUE
J 0
(12 12);
DISPLAY 0.468085 (12 12);
PAINT GREEN (12 12);
DISPLAY INVISIBLE (12 12);
FORCEPROP 2 LAST CDS_XR_PAGE_TITLE CR-207 : @BASEBOARD_FAB2_LIB.BASEBOARD_FAB2(SCH_1):PAGE207
J 0
(-7890 5250);
DISPLAY 0.638298 (-7890 5250);
PAINT PINK (-7890 5250);
DISPLAY INVISIBLE (-7890 5250);
WIRE 16 -1 (-750 950)(-750 1000);
WIRE 16 -1 (-750 950)(-1100 950);
WIRE 16 -1 (-750 850)(-750 950);
WIRE 16 -1 (-1250 950)(-1100 950);
WIRE 16 -1 (-1100 850)(-1100 950);
WIRE 16 -1 (-1250 950)(-1250 325);
WIRE 16 -1 (-1275 950)(-1250 950);
WIRE 16 -1 (-3750 325)(-1250 325);
WIRE 16 -1 (-3750 1400)(-3750 325);
WIRE 16 -1 (-3650 1400)(-3750 1400);
WIRE 16 -1 (-750 475)(-750 500);
WIRE 16 -1 (-750 500)(-1100 500);
WIRE 16 -1 (-750 650)(-750 500);
WIRE 16 -1 (-1100 500)(-1100 650);
WIRE 16 -1 (-2400 3150)(-2400 3300);
WIRE 16 -1 (-2400 3300)(-2400 3350);
WIRE 16 -1 (-2400 3300)(-2625 3300);
WIRE 16 -1 (-2400 3350)(-2400 3400);
WIRE 16 -1 (-2625 3350)(-2400 3350);
WIRE 16 -1 (-2400 3400)(-2400 3450);
WIRE 16 -1 (-2625 3400)(-2400 3400);
WIRE 16 -1 (-2400 3450)(-2625 3450);
WIRE 16 -1 (-2450 625)(-2450 700);
WIRE 16 -1 (-2450 700)(-2450 750);
WIRE 16 -1 (-2450 700)(-2650 700);
WIRE 16 -1 (-2450 750)(-2450 800);
WIRE 16 -1 (-2450 750)(-2650 750);
WIRE 16 -1 (-2450 800)(-2450 850);
WIRE 16 -1 (-2450 800)(-2650 800);
WIRE 16 -1 (-2650 850)(-2450 850);
WIRE 16 -1 (-6550 4475)(-6550 4350);
WIRE 16 -1 (-6425 4350)(-6550 4350);
WIRE 16 -1 (-6550 4350)(-6725 4350);
WIRE 16 -1 (-7025 4350)(-6725 4350);
WIRE 16 -1 (-6725 4225)(-6725 4350);
WIRE 16 -1 (-6425 4350)(-6150 4350);
WIRE 16 -1 (-6425 4225)(-6425 4350);
WIRE 16 -1 (-6150 4350)(-5850 4350);
WIRE 16 -1 (-6150 4225)(-6150 4350);
WIRE 16 -1 (-7025 4225)(-7025 4350);
WIRE 16 -1 (-4100 4350)(-5850 4350);
WIRE 16 -1 (-5850 4225)(-5850 4350);
WIRE 16 -1 (-4100 4350)(-4100 4300);
WIRE 16 -1 (-3625 4350)(-4100 4350);
WIRE 16 -1 (-3625 4300)(-4100 4300);
WIRE 16 -1 (-7025 3850)(-7025 3775);
WIRE 16 -1 (-7025 3850)(-6725 3850);
WIRE 16 -1 (-7025 4025)(-7025 3850);
WIRE 16 -1 (-6725 3850)(-6425 3850);
WIRE 16 -1 (-6725 4025)(-6725 3850);
WIRE 16 -1 (-6425 3850)(-6150 3850);
WIRE 16 -1 (-6425 4025)(-6425 3850);
WIRE 16 -1 (-6150 3850)(-5850 3850);
WIRE 16 -1 (-6150 4025)(-6150 3850);
WIRE 16 -1 (-5850 3850)(-5550 3850);
WIRE 16 -1 (-5850 4025)(-5850 3850);
WIRE 16 -1 (-5550 3850)(-5100 3850);
WIRE 16 -1 (-5550 4000)(-5550 3850);
WIRE 16 -1 (-4725 3850)(-5100 3850);
WIRE 16 -1 (-5100 4050)(-5100 3850);
WIRE 16 -1 (-4725 4050)(-4725 3850);
WIRE 16 -1 (-6300 1850)(-6300 1750);
WIRE 16 -1 (-6300 1750)(-6025 1750);
WIRE 16 -1 (-6575 1750)(-6300 1750);
WIRE 16 -1 (-6300 1650)(-6300 1750);
WIRE 16 -1 (-6575 1750)(-6875 1750);
WIRE 16 -1 (-6575 1650)(-6575 1750);
WIRE 16 -1 (-5725 1750)(-6025 1750);
WIRE 16 -1 (-6025 1650)(-6025 1750);
WIRE 16 -1 (-4125 1750)(-5725 1750);
WIRE 16 -1 (-5725 1625)(-5725 1750);
WIRE 16 -1 (-6875 1650)(-6875 1750);
WIRE 16 -1 (-4125 1750)(-4125 1700);
WIRE 16 -1 (-3650 1750)(-4125 1750);
WIRE 16 -1 (-3650 1700)(-4125 1700);
WIRE 16 -1 (-6875 1200)(-6875 1275);
WIRE 16 -1 (-6875 1275)(-6575 1275);
WIRE 16 -1 (-6875 1450)(-6875 1275);
WIRE 16 -1 (-6575 1275)(-6300 1275);
WIRE 16 -1 (-6575 1450)(-6575 1275);
WIRE 16 -1 (-6300 1275)(-6025 1275);
WIRE 16 -1 (-6300 1450)(-6300 1275);
WIRE 16 -1 (-5725 1275)(-6025 1275);
WIRE 16 -1 (-6025 1450)(-6025 1275);
WIRE 16 -1 (-5725 1275)(-5450 1275);
WIRE 16 -1 (-5725 1425)(-5725 1275);
WIRE 16 -1 (-5000 1275)(-5450 1275);
WIRE 16 -1 (-5450 1425)(-5450 1275);
WIRE 16 -1 (-4600 1275)(-5000 1275);
WIRE 16 -1 (-5000 1500)(-5000 1275);
WIRE 16 -1 (-4600 1475)(-4600 1275);
WIRE 16 -1 (-4225 4650)(-4225 4750);
WIRE 16 -1 (-4225 4650)(-4725 4650);
WIRE 16 -1 (-4225 4200)(-4225 4650);
WIRE 16 -1 (-4225 4200)(-4225 4100);
WIRE 16 -1 (-3625 4200)(-4225 4200);
WIRE 16 -1 (-4725 4650)(-5100 4650);
WIRE 16 -1 (-4725 4250)(-4725 4650);
WIRE 16 -1 (-5300 4650)(-5100 4650);
WIRE 16 -1 (-5100 4200)(-5100 4650);
WIRE 16 -1 (-4225 4100)(-3625 4100);
WIRE 16 -1 (-4750 2050)(-4750 2150);
WIRE 16 -1 (-4750 2050)(-5000 2050);
WIRE 16 -1 (-4750 2050)(-4600 2050);
WIRE 16 -1 (-3975 2050)(-4600 2050);
WIRE 16 -1 (-4600 1675)(-4600 2050);
WIRE 16 -1 (-5000 1650)(-5000 2050);
WIRE 16 -1 (-5200 2050)(-5000 2050);
WIRE 16 -1 (-3975 1600)(-3975 2050);
WIRE 16 -1 (-3975 1600)(-3975 1500);
WIRE 16 -1 (-3650 1600)(-3975 1600);
WIRE 16 -1 (-3975 1500)(-3650 1500);
WIRE 16 -1 (-450 3950)(-450 3900);
WIRE 16 -1 (-650 3550)(-650 3600);
WIRE 16 -1 (-650 3550)(-1100 3550);
WIRE 16 -1 (-650 3450)(-650 3550);
WIRE 16 -1 (-1250 3550)(-1100 3550);
WIRE 16 -1 (-1100 3450)(-1100 3550);
WIRE 16 -1 (-1250 3550)(-1250 2800);
WIRE 16 -1 (-1325 3550)(-1250 3550);
WIRE 16 -1 (-1250 2800)(-3775 2800);
WIRE 16 -1 (-3775 2800)(-3775 4000);
WIRE 16 -1 (-3775 4000)(-3625 4000);
WIRE 16 -1 (-700 1250)(-700 1325);
WIRE 16 -1 (-3850 3250)(-3850 3075);
WIRE 16 -1 (-2125 3750)(-2125 3700);
WIRE 16 -1 (-2225 2900)(-2225 2925);
WIRE 16 -1 (-3825 650)(-3825 550);
WIRE 16 -1 (-2075 1150)(-2075 1100);
WIRE 16 -1 (-1925 400)(-1925 425);
WIRE 16 -1 (-650 3050)(-650 3100);
WIRE 16 -1 (-650 3100)(-1100 3100);
WIRE 16 -1 (-650 3250)(-650 3100);
WIRE 16 -1 (-1100 3100)(-1100 3250);
WIRE 16 -1 (-5450 2050)(-5400 2050);
WIRE 16 -1 (-5450 1800)(-5450 1625);
WIRE 16 -1 (-5450 1800)(-5450 2050);
WIRE 16 -1 (-3650 1800)(-5450 1800);
FORCEPROP 2 LAST SIG_NAME VR_PVCCIN_CPU1_PH2_VCIN
J 0
(-4585 1810);
DISPLAY 0.638298 (-4585 1810);
PAINT ORANGE (-4585 1810);
FORCEPROP 2 LASTPROP $XRERR UNIQUE?
J 0
(-4825 1810);
DISPLAY 0.638298 (-4825 1810);
PAINT MONO (-4825 1810);
DISPLAY INVISIBLE (-4825 1810);
WIRE 3 2175 (-5500 1825)(-5050 1825);
WIRE 3 2175 (-5050 2100)(-5050 1825);
WIRE 3 2175 (-5500 2100)(-5500 1825);
WIRE 3 2175 (-5500 2100)(-5050 2100);
WIRE 16 -1 (-2650 1800)(-1000 1800);
FORCEPROP 2 LAST SIG_NAME ISENSE_PVCCIN_CPU1_PH2_IMON
J 0
(-2378 1815);
DISPLAY 0.617021 (-2378 1815);
PAINT ORANGE (-2378 1815);
WIRE 3 2175 (-2225 1025)(-1825 1025);
WIRE 3 2175 (-1825 1475)(-1825 1025);
WIRE 3 2175 (-2225 1475)(-2225 1025);
WIRE 3 2175 (-2225 1475)(-1825 1475);
WIRE 16 -1 (-2650 1500)(-2650 1300);
WIRE 16 -1 (-2650 1500)(-2075 1500);
FORCEPROP 2 LAST SIG_NAME A_TSENSE_PVCCIN_CPU1
J 0
(-2297 1519);
DISPLAY 0.617021 (-2297 1519);
PAINT ORANGE (-2297 1519);
WIRE 16 -1 (-2075 1350)(-2075 1500);
WIRE 16 -1 (-2075 1500)(-1550 1500);
WIRE 16 -1 (-700 1600)(-700 1525);
WIRE 16 -1 (-2650 1600)(-700 1600);
FORCEPROP 0 LAST SIG_NAME VR_PVCCIN_CPU1_PH2_OCSET
J 0
(-2510 1610);
DISPLAY 0.617021 (-2510 1610);
PAINT ORANGE (-2510 1610);
FORCEPROP 2 LASTPROP $XRERR UNIQUE?
J 0
(-2750 1610);
DISPLAY 0.638298 (-2750 1610);
PAINT MONO (-2750 1610);
DISPLAY INVISIBLE (-2750 1610);
WIRE 16 -1 (-450 4200)(-2625 4200);
FORCEPROP 0 LAST SIG_NAME VR_PVCCIN_CPU1_PH1_OCSET
J 0
(-2485 4210);
DISPLAY 0.617021 (-2485 4210);
PAINT ORANGE (-2485 4210);
FORCEPROP 2 LASTPROP $XRERR UNIQUE?
J 0
(-2725 4210);
DISPLAY 0.638298 (-2725 4210);
PAINT MONO (-2725 4210);
DISPLAY INVISIBLE (-2725 4210);
WIRE 16 -1 (-450 4200)(-450 4150);
WIRE 16 -1 (-3825 850)(-3825 1050);
WIRE 16 -1 (-3650 1050)(-3825 1050);
WIRE 16 -1 (-3825 1050)(-3825 2275);
WIRE 16 -1 (-3825 2275)(-1025 2275);
FORCEPROP 2 LAST SIG_NAME VR_PVCCIN_CPU1_AIREF2
J 2
(-3179 2294);
DISPLAY 0.617021 (-3179 2294);
PAINT ORANGE (-3179 2294);
WIRE 16 2175 (-5775 650)(-5000 650);
WIRE 16 2175 (-5000 1125)(-5000 650);
WIRE 16 2175 (-5775 1125)(-5775 650);
WIRE 16 2175 (-5775 1125)(-5000 1125);
WIRE 16 -1 (-5550 1025)(-5550 975);
WIRE 16 -1 (-4800 1025)(-5550 1025);
FORCEPROP 2 LAST SIG_NAME VR_PVCCIN_CPU1_PH2_BOOT
J 0
(-5565 1035);
DISPLAY 0.617021 (-5565 1035);
PAINT ORANGE (-5565 1035);
FORCEPROP 2 LASTPROP $XRERR UNIQUE?
J 0
(-5805 1035);
DISPLAY 0.638298 (-5805 1035);
PAINT MONO (-5805 1035);
DISPLAY INVISIBLE (-5805 1035);
WIRE 3 682 (-2600 1550)(-2500 1550);
WIRE 16 2175 (-5175 1725)(-4425 1725);
WIRE 16 2175 (-4425 1725)(-4425 1325);
WIRE 16 2175 (-5175 1725)(-5175 1325);
WIRE 16 2175 (-5175 1325)(-4425 1325);
WIRE 3 682 (-4950 1700)(-4950 1425);
WIRE 3 682 (-5050 1700)(-4950 1700);
WIRE 3 682 (-4950 1425)(-5050 1425);
WIRE 3 682 (-5050 1425)(-5050 1700);
WIRE 16 -1 (-2225 3500)(-2225 3550);
WIRE 16 -1 (-1625 3550)(-2225 3550);
FORCEPROP 0 LAST VOLTAGE 5
J 0
(-2200 3625);
DISPLAY 1.021277 (-2200 3625);
PAINT SKYBLUE (-2200 3625);
DISPLAY INVISIBLE (-2200 3625);
WIRE 16 -1 (-2625 3550)(-2225 3550);
FORCEPROP 2 LAST SIG_NAME VR_PVCCIN_CPU1_PHASE1
J 0
(-2465 3560);
DISPLAY 0.617021 (-2465 3560);
PAINT ORANGE (-2465 3560);
FORCEPROP 2 LASTPROP $XRERR UNIQUE?
J 0
(-2705 3560);
DISPLAY 0.638298 (-2705 3560);
PAINT MONO (-2705 3560);
DISPLAY INVISIBLE (-2705 3560);
WIRE 3 2175 (-5600 4450)(-5200 4450);
WIRE 3 2175 (-5200 4700)(-5200 4450);
WIRE 3 2175 (-5600 4700)(-5600 4450);
WIRE 3 2175 (-5600 4700)(-5200 4700);
WIRE 3 2175 (-2350 3600)(-1675 3600);
WIRE 3 2175 (-1675 3600)(-1675 2825);
WIRE 3 2175 (-2350 3600)(-2350 2825);
WIRE 3 2175 (-2350 2825)(-1675 2825);
WIRE 16 -1 (-2225 3200)(-2225 3175);
WIRE 16 -1 (-2225 3200)(-1550 3200);
FORCEPROP 2 LAST SIG_NAME VR_PVCCIN_CPU1_PHASE1_RC
J 0
(-2190 3210);
DISPLAY 0.617021 (-2190 3210);
PAINT ORANGE (-2190 3210);
FORCEPROP 2 LASTPROP $XRERR UNIQUE?
J 0
(-1520 3200);
DISPLAY 0.638298 (-1520 3200);
PAINT MONO (-1520 3200);
DISPLAY INVISIBLE (-1520 3200);
WIRE 16 -1 (-2225 3300)(-2225 3200);
WIRE 16 -1 (-1925 700)(-2375 700);
FORCEPROP 2 LAST SIG_NAME VR_PVCCIN_CPU1_PHASE2_RC
J 0
(-2415 710);
DISPLAY 0.510638 (-2415 710);
PAINT ORANGE (-2415 710);
FORCEPROP 2 LASTPROP $XRERR UNIQUE?
J 0
(-2615 700);
DISPLAY 0.638298 (-2615 700);
PAINT MONO (-2615 700);
DISPLAY INVISIBLE (-2615 700);
WIRE 16 -1 (-1925 675)(-1925 700);
WIRE 16 -1 (-1925 725)(-1925 700);
WIRE 16 -1 (-4475 3850)(-3625 3850);
FORCEPROP 0 LAST SIG_NAME TP_PVCCINC_CPU1_PH1_GL_0
J 0
(-4460 3860);
DISPLAY 0.617021 (-4460 3860);
PAINT ORANGE (-4460 3860);
FORCEPROP 2 LASTPROP $XRERR UNIQUE?
J 0
(-4715 3850);
DISPLAY 0.638298 (-4715 3850);
PAINT MONO (-4715 3850);
DISPLAY INVISIBLE (-4715 3850);
WIRE 3 2175 (-4900 850)(-4475 850);
WIRE 3 2175 (-4475 1100)(-4475 850);
WIRE 3 2175 (-4900 1100)(-4900 850);
WIRE 3 2175 (-4900 1100)(-4475 1100);
WIRE 16 2175 (-5925 3725)(-5050 3725);
WIRE 16 2175 (-5050 3725)(-5050 3300);
WIRE 16 2175 (-5925 3725)(-5925 3300);
WIRE 16 2175 (-5925 3300)(-5050 3300);
WIRE 3 2175 (-2275 4075)(-1850 4075);
WIRE 3 2175 (-1850 4075)(-1850 3625);
WIRE 3 2175 (-2275 4075)(-2275 3625);
WIRE 3 2175 (-2275 3625)(-1850 3625);
WIRE 16 -1 (-2625 4100)(-2625 3900);
WIRE 16 -1 (-2625 4100)(-2125 4100);
FORCEPROP 2 LAST SIG_NAME A_TSENSE_PVCCIN_CPU1
J 0
(-2488 4110);
DISPLAY 0.617021 (-2488 4110);
PAINT ORANGE (-2488 4110);
WIRE 16 -1 (-2125 4100)(-1600 4100);
WIRE 16 -1 (-2125 3950)(-2125 4100);
WIRE 16 -1 (-3625 3900)(-4500 3900);
FORCEPROP 0 LAST SIG_NAME TP_PVCCINC_CPU1_PH1_GL_1
J 0
(-4485 3910);
DISPLAY 0.617021 (-4485 3910);
PAINT ORANGE (-4485 3910);
FORCEPROP 2 LASTPROP $XRERR UNIQUE?
J 0
(-4740 3900);
DISPLAY 0.638298 (-4740 3900);
PAINT MONO (-4740 3900);
DISPLAY INVISIBLE (-4740 3900);
WIRE 16 -1 (-5550 4650)(-5500 4650);
WIRE 16 -1 (-5550 4400)(-5550 4650);
WIRE 16 -1 (-5550 4400)(-3625 4400);
FORCEPROP 0 LAST VOLTAGE 5
J 0
(-5025 4475);
DISPLAY 1.021277 (-5025 4475);
PAINT SKYBLUE (-5025 4475);
DISPLAY INVISIBLE (-5025 4475);
FORCEPROP 2 LAST SIG_NAME VR_PVCCIN_CPU1_PH1_VCIN
J 0
(-5490 4410);
DISPLAY 0.617021 (-5490 4410);
PAINT ORANGE (-5490 4410);
FORCEPROP 2 LASTPROP $XRERR UNIQUE?
J 0
(-5730 4410);
DISPLAY 0.638298 (-5730 4410);
PAINT MONO (-5730 4410);
DISPLAY INVISIBLE (-5730 4410);
WIRE 16 -1 (-5550 4200)(-5550 4400);
WIRE 16 -1 (-2625 4425)(-2625 4400);
WIRE 16 -1 (-1450 4425)(-2625 4425);
FORCEPROP 2 LAST SIG_NAME ISENSE_PVCCIN_CPU1_PH1_IMON
J 0
(-2313 4435);
DISPLAY 0.617021 (-2313 4435);
PAINT ORANGE (-2313 4435);
WIRE 3 682 (-2550 4150)(-2450 4150);
WIRE 16 -1 (-5675 3400)(-4000 3400);
FORCEPROP 0 LAST VOLTAGE 5
J 0
(-5575 3475);
DISPLAY 1.021277 (-5575 3475);
PAINT SKYBLUE (-5575 3475);
DISPLAY INVISIBLE (-5575 3475);
FORCEPROP 2 LAST SIG_NAME VR_PVCCIN_CPU1_PH1_PHASE
J 0
(-5640 3410);
DISPLAY 0.617021 (-5640 3410);
PAINT ORANGE (-5640 3410);
FORCEPROP 2 LASTPROP $XRERR UNIQUE?
J 0
(-5880 3410);
DISPLAY 0.638298 (-5880 3410);
PAINT MONO (-5880 3410);
DISPLAY INVISIBLE (-5880 3410);
WIRE 16 -1 (-4000 3500)(-4000 3400);
WIRE 16 -1 (-3625 3500)(-4000 3500);
WIRE 16 -1 (-5675 3675)(-4925 3675);
FORCEPROP 2 LAST SIG_NAME VR_PVCCIN_CPU1_PH1_BOOT
J 0
(-5640 3685);
DISPLAY 0.617021 (-5640 3685);
PAINT ORANGE (-5640 3685);
FORCEPROP 2 LASTPROP $XRERR UNIQUE?
J 0
(-5880 3685);
DISPLAY 0.638298 (-5880 3685);
PAINT MONO (-5880 3685);
DISPLAY INVISIBLE (-5880 3685);
WIRE 16 -1 (-5675 3600)(-5675 3675);
WIRE 3 2175 (-5025 3500)(-4650 3500);
WIRE 3 2175 (-4650 3725)(-4650 3500);
WIRE 3 2175 (-5025 3725)(-5025 3500);
WIRE 3 2175 (-5025 3725)(-4650 3725);
WIRE 16 -1 (-6400 3750)(-3625 3750);
WIRE 3 682 (-5050 3975)(-5150 3975);
WIRE 3 682 (-5050 4275)(-5050 3975);
WIRE 3 682 (-5150 3975)(-5150 4275);
WIRE 3 682 (-5150 4275)(-5050 4275);
WIRE 16 2175 (-5225 3900)(-4525 3900);
WIRE 16 2175 (-4525 4300)(-4525 3900);
WIRE 16 2175 (-5225 4300)(-5225 3900);
WIRE 16 2175 (-5225 4300)(-4525 4300);
WIRE 16 -1 (-3850 3450)(-3850 3650);
WIRE 16 -1 (-3625 3650)(-3850 3650);
WIRE 16 -1 (-3850 3650)(-3850 4750);
WIRE 16 -1 (-1525 4750)(-3850 4750);
FORCEPROP 2 LAST SIG_NAME VR_PVCCIN_CPU1_AIREF1
J 2
(-3178 4785);
DISPLAY 0.617021 (-3178 4785);
PAINT ORANGE (-3178 4785);
WIRE 16 -1 (-1925 925)(-1925 950);
WIRE 16 -1 (-1925 950)(-1575 950);
WIRE 16 -1 (-2650 950)(-1925 950);
FORCEPROP 0 LAST VOLTAGE 5
J 0
(-2375 1025);
DISPLAY 1.021277 (-2375 1025);
PAINT SKYBLUE (-2375 1025);
DISPLAY INVISIBLE (-2375 1025);
FORCEPROP 2 LAST SIG_NAME VR_PVCCIN_CPU1_PHASE2
J 0
(-2540 960);
DISPLAY 0.617021 (-2540 960);
PAINT ORANGE (-2540 960);
FORCEPROP 2 LASTPROP $XRERR UNIQUE?
J 0
(-2780 960);
DISPLAY 0.638298 (-2780 960);
PAINT MONO (-2780 960);
DISPLAY INVISIBLE (-2780 960);
WIRE 16 -1 (-4600 1025)(-3875 1025);
FORCEPROP 2 LAST SIG_NAME VR_PVCCIN_CPU1_PH2_BOOT_R
J 0
(-4465 1035);
DISPLAY 0.617021 (-4465 1035);
PAINT ORANGE (-4465 1035);
FORCEPROP 2 LASTPROP $XRERR UNIQUE?
J 0
(-4705 1035);
DISPLAY 0.638298 (-4705 1035);
PAINT MONO (-4705 1035);
DISPLAY INVISIBLE (-4705 1035);
WIRE 16 -1 (-3650 950)(-3875 950);
WIRE 16 -1 (-3875 950)(-3875 1025);
WIRE 16 -1 (-6300 1150)(-3650 1150);
FORCEPROP 2 LAST SIG_NAME VR_PVCCIN_CPU1_PWM2
J 0
(-6313 1160);
DISPLAY 0.617021 (-6313 1160);
PAINT ORANGE (-6313 1160);
WIRE 16 -1 (-5550 775)(-3875 775);
FORCEPROP 0 LAST VOLTAGE 5
J 0
(-5425 850);
DISPLAY 1.021277 (-5425 850);
PAINT SKYBLUE (-5425 850);
DISPLAY INVISIBLE (-5425 850);
FORCEPROP 2 LAST SIG_NAME VR_PVCCIN_CPU1_PH2_PHASE
J 0
(-5515 785);
DISPLAY 0.617021 (-5515 785);
PAINT ORANGE (-5515 785);
FORCEPROP 2 LASTPROP $XRERR UNIQUE?
J 0
(-5755 785);
DISPLAY 0.638298 (-5755 785);
PAINT MONO (-5755 785);
DISPLAY INVISIBLE (-5755 785);
WIRE 16 -1 (-3875 900)(-3875 775);
WIRE 16 -1 (-3650 900)(-3875 900);
WIRE 16 -1 (-4375 1250)(-3650 1250);
FORCEPROP 0 LAST SIG_NAME TP_PVCCINC_CPU1_PH2_GL_0
J 0
(-4360 1260);
DISPLAY 0.617021 (-4360 1260);
PAINT ORANGE (-4360 1260);
FORCEPROP 2 LASTPROP $XRERR UNIQUE?
J 0
(-4615 1250);
DISPLAY 0.638298 (-4615 1250);
PAINT MONO (-4615 1250);
DISPLAY INVISIBLE (-4615 1250);
WIRE 16 -1 (-3650 1300)(-4400 1300);
FORCEPROP 0 LAST SIG_NAME TP_PVCCINC_CPU1_PH2_GL_1
J 0
(-4385 1310);
DISPLAY 0.617021 (-4385 1310);
PAINT ORANGE (-4385 1310);
FORCEPROP 2 LASTPROP $XRERR UNIQUE?
J 0
(-4640 1300);
DISPLAY 0.638298 (-4640 1300);
PAINT MONO (-4640 1300);
DISPLAY INVISIBLE (-4640 1300);
WIRE 3 2175 (-3125 1000)(-1600 1000);
WIRE 3 2175 (-1600 1000)(-1600 350);
WIRE 3 2175 (-3125 1000)(-3125 350);
WIRE 3 2175 (-3125 350)(-1600 350);
WIRE 16 -1 (-3625 3550)(-4000 3550);
WIRE 16 -1 (-4000 3550)(-4000 3675);
WIRE 16 -1 (-4725 3675)(-4000 3675);
FORCEPROP 2 LAST SIG_NAME VR_PVCCIN_CPU1_PH1_BOOT_R
J 0
(-4640 3685);
DISPLAY 0.617021 (-4640 3685);
PAINT ORANGE (-4640 3685);
FORCEPROP 2 LASTPROP $XRERR UNIQUE?
J 0
(-4880 3685);
DISPLAY 0.638298 (-4880 3685);
PAINT MONO (-4880 3685);
DISPLAY INVISIBLE (-4880 3685);
DOT 1 (-6575 1750);
DOT 1 (-6725 3850);
DOT 1 (-7025 3850);
DOT 1 (-6725 4350);
DOT 1 (-5000 2050);
DOT 1 (-4600 2050);
DOT 1 (-5450 1800);
DOT 1 (-4125 1750);
DOT 1 (-5000 1275);
DOT 1 (-4750 2050);
DOT 1 (-1250 950);
DOT 1 (-6300 1275);
DOT 1 (-4225 4200);
DOT 1 (-1925 700);
DOT 1 (-1250 3550);
DOT 1 (-2225 3200);
DOT 1 (-5850 3850);
DOT 1 (-5850 4350);
DOT 1 (-5550 3850);
DOT 1 (-6025 1275);
DOT 1 (-6025 1750);
DOT 1 (-5725 1275);
DOT 1 (-5725 1750);
DOT 1 (-5450 1275);
DOT 1 (-6875 1275);
DOT 1 (-6575 1275);
DOT 1 (-6300 1750);
DOT 1 (-6150 3850);
DOT 1 (-6150 4350);
DOT 1 (-6425 3850);
DOT 1 (-6425 4350);
DOT 1 (-3825 1050);
DOT 1 (-6550 4350);
DOT 1 (-4100 4350);
DOT 1 (-2450 700);
DOT 1 (-2450 750);
DOT 1 (-2450 800);
DOT 1 (-1925 950);
DOT 1 (-2075 1500);
DOT 1 (-2400 3350);
DOT 1 (-2400 3300);
DOT 1 (-2400 3400);
DOT 1 (-2225 3550);
DOT 1 (-2125 4100);
DOT 1 (-750 950);
DOT 1 (-1100 3550);
DOT 1 (-650 3550);
DOT 1 (-5550 4400);
DOT 1 (-3975 1600);
DOT 1 (-4225 4650);
DOT 1 (-4725 4650);
DOT 1 (-3850 3650);
DOT 1 (-5100 4650);
DOT 1 (-5100 3850);
DOT 1 (-650 3100);
DOT 1 (-750 500);
DOT 1 (-1100 950);
FORCENOTE
TP FAB1 CHANGE TO 0 OHM 0107
(-5450 2125) 0;
DISPLAY LEFT (-5450 2125);
DISPLAY 0.638298 (-5450 2125);
PAINT RED (-5450 2125);
FORCENOTE
TP FAB1 CHANGE RES TO 1 OHM 0603 0107
(-3100 375) 0;
DISPLAY LEFT (-3100 375);
DISPLAY 0.638298 (-3100 375);
PAINT RED (-3100 375);
FORCENOTE
TP FAB1 ADD NET NAME 12/04
(-3050 500) 0;
DISPLAY LEFT (-3050 500);
DISPLAY 0.851064 (-3050 500);
PAINT RED (-3050 500);
FORCENOTE
TDA21470
(-3325 1850) 0;
DISPLAY LEFT (-3325 1850);
DISPLAY 1.021277 (-3325 1850);
PAINT SKYBLUE (-3325 1850);
FORCENOTE
TDA21470
(-3275 4475) 0;
DISPLAY LEFT (-3275 4475);
DISPLAY 1.021277 (-3275 4475);
PAINT SKYBLUE (-3275 4475);
FORCENOTE
TP FAB1 CHANGE PN 0310
(-4875 1375) 0;
DISPLAY LEFT (-4875 1375);
DISPLAY 1.021277 (-4875 1375);
PAINT RED (-4875 1375);
FORCENOTE
ROOM=PROC_VRD_VCCIN_CPU1
(-7816 343) 0;
DISPLAY LEFT (-7816 343);
DISPLAY 2.510638 (-7816 343);
PAINT PURPLE (-7816 343);
FORCENOTE
TP FAB1 CO-LAY WITH TI PARTS 11/16
(-5025 525) 0;
DISPLAY LEFT (-5025 525);
DISPLAY 0.851064 (-5025 525);
PAINT RED (-5025 525);
FORCENOTE
TP FAB1 DEL NET 0309
(-2475 1550) 0;
DISPLAY LEFT (-2475 1550);
DISPLAY 1.021277 (-2475 1550);
PAINT RED (-2475 1550);
FORCENOTE
TP FAB1 CHANGE TO 0 OHM 0107
(-5600 4725) 0;
DISPLAY LEFT (-5600 4725);
DISPLAY 0.638298 (-5600 4725);
PAINT RED (-5600 4725);
FORCENOTE
PLACE ON TOP
(-5255 3800) 0;
DISPLAY LEFT (-5255 3800);
DISPLAY 1.553191 (-5255 3800);
PAINT PURPLE (-5255 3800);
FORCENOTE
TP FAB1 CO-LAY WITH TI PARTS 11/16
(-5050 3225) 0;
DISPLAY LEFT (-5050 3225);
DISPLAY 0.851064 (-5050 3225);
PAINT RED (-5050 3225);
FORCENOTE
SPOF
(-5755 3175) 0;
DISPLAY LEFT (-5755 3175);
DISPLAY 1.936170 (-5755 3175);
PAINT PURPLE (-5755 3175);
FORCENOTE
TP FAB1 CHANGE L1D3 PN 0122
(-1725 1125) 0;
DISPLAY LEFT (-1725 1125);
DISPLAY 1.021277 (-1725 1125);
PAINT RED (-1725 1125);
FORCENOTE
PLACE ON TOP
(-5155 1200) 0;
DISPLAY LEFT (-5155 1200);
DISPLAY 1.553191 (-5155 1200);
PAINT PURPLE (-5155 1200);
FORCENOTE
TP FAB1 DEL NET 0309
(-2425 4150) 0;
DISPLAY LEFT (-2425 4150);
DISPLAY 1.021277 (-2425 4150);
PAINT RED (-2425 4150);
FORCENOTE
SPOF
(-6105 1025) 0;
DISPLAY LEFT (-6105 1025);
DISPLAY 1.808511 (-6105 1025);
PAINT PURPLE (-6105 1025);
FORCENOTE
TP FAB1 CHANGE RES TO 1 OHM 0603 0107
(-2350 2675) 0;
DISPLAY LEFT (-2350 2675);
DISPLAY 0.638298 (-2350 2675);
PAINT RED (-2350 2675);
FORCENOTE
TP FAB1 CO-LAY WITH TI PARTS 11/16
(-2350 2725) 0;
DISPLAY LEFT (-2350 2725);
DISPLAY 0.553191 (-2350 2725);
PAINT RED (-2350 2725);
FORCENOTE
TP FAB1 CHANGE PN 0310
(-5175 4300) 0;
DISPLAY LEFT (-5175 4300);
DISPLAY 1.021277 (-5175 4300);
PAINT RED (-5175 4300);
FORCENOTE
TP FAB1 ADD NET NAME 12/04
(-1625 3000) 0;
DISPLAY LEFT (-1625 3000);
DISPLAY 0.553191 (-1625 3000);
PAINT RED (-1625 3000);
FORCENOTE
TP FAB1 CHANGE L1E1 PN 0122
(-1775 3725) 0;
DISPLAY LEFT (-1775 3725);
DISPLAY 1.021277 (-1775 3725);
PAINT RED (-1775 3725);
FORCENOTE
TP FAB1 CO-LAY WITH TI PARTS 11/16
(-1825 3850) 0;
DISPLAY LEFT (-1825 3850);
DISPLAY 0.851064 (-1825 3850);
PAINT RED (-1825 3850);
FORCENOTE
TP FAB1 CO-LAY WITH TI PARTS 11/16
(-1575 350) 0;
DISPLAY LEFT (-1575 350);
DISPLAY 0.851064 (-1575 350);
PAINT RED (-1575 350);
FORCENOTE
TP FAB1 CO-LAY WITH TI PARTS 11/16
(-1800 1200) 0;
DISPLAY LEFT (-1800 1200);
DISPLAY 0.851064 (-1800 1200);
PAINT RED (-1800 1200);
QUIT
